G04 ================== begin FILE IDENTIFICATION RECORD ==================*
G04 Layout Name:  12004-1.brd*
G04 Film Name:    L4VCC*
G04 File Format:  Gerber RS274X*
G04 File Origin:  Cadence Allegro 16.2-S033*
G04 Origin Date:  Tue Oct 16 14:36:05 2012*
G04 *
G04 Layer:  VIA CLASS/L4VCC*
G04 Layer:  PIN/L4VCC*
G04 Layer:  PACKAGE GEOMETRY/PWRVCC*
G04 Layer:  ETCH/L4VCC*
G04 Layer:  DRAWING FORMAT/LAYER_PCB_STORY*
G04 Layer:  DRAWING FORMAT/LAYER_L4VCC*
G04 *
G04 Offset:    (0.00 0.00)*
G04 Mirror:    No*
G04 Mode:      Negative*
G04 Rotation:  0*
G04 FullContactRelief:  No*
G04 UndefLineWidth:     6.00*
G04 ================== end FILE IDENTIFICATION RECORD ====================*
%FSLAX35Y35*MOIN*%
%IR0*IPPOS*OFA0.00000B0.00000*MIA0B0*SFA1.00000B1.00000*%
%ADD16C,.03*%
%ADD15C,.032*%
%ADD17C,.06*%
%ADD21C,.09*%
%ADD18C,.063*%
%ADD13C,.036*%
%ADD24C,.073*%
%ADD20C,.067*%
%ADD23C,.089*%
%AMMACRO25*
4,1,15,.00398,.00044,
.003999,.000208,
.004004,-.000025,
.003996,-.000258,
.00398,-.00044,
.00483,-.00129,
.004897,-.001007,
.004947,-.000721,
.004981,-.000432,
.004997,-.000141,
.004997,.000149,
.00498,.00044,
.004946,.000729,
.004895,.001015,
.00483,.00129,
.00398,.00044,
90.*
4,1,15,.00044,-.00398,
.000208,-.003999,
-.000025,-.004004,
-.000258,-.003996,
-.00044,-.00398,
-.00129,-.00483,
-.001007,-.004897,
-.000721,-.004947,
-.000432,-.004981,
-.000141,-.004997,
.000149,-.004997,
.00044,-.00498,
.000729,-.004946,
.001015,-.004895,
.00129,-.00483,
.00044,-.00398,
90.*
4,1,15,-.00398,-.00044,
-.003999,-.000208,
-.004004,.000025,
-.003996,.000258,
-.00398,.00044,
-.00483,.00129,
-.004897,.001007,
-.004947,.000721,
-.004981,.000432,
-.004997,.000141,
-.004997,-.000149,
-.00498,-.00044,
-.004946,-.000729,
-.004895,-.001015,
-.00483,-.00129,
-.00398,-.00044,
90.*
4,1,15,-.00044,.00398,
-.000208,.003999,
.000025,.004004,
.000258,.003996,
.00044,.00398,
.00129,.00483,
.001007,.004897,
.000721,.004947,
.000432,.004981,
.000141,.004997,
-.000149,.004997,
-.00044,.00498,
-.000729,.004946,
-.001015,.004895,
-.00129,.00483,
-.00044,.00398,
90.*
%
%ADD25MACRO25*%
%AMMACRO11*
4,1,15,.00398,.00044,
.003999,.000208,
.004004,-.000025,
.003996,-.000258,
.00398,-.00044,
.00483,-.00129,
.004897,-.001007,
.004947,-.000721,
.004981,-.000432,
.004997,-.000141,
.004997,.000149,
.00498,.00044,
.004946,.000729,
.004895,.001015,
.00483,.00129,
.00398,.00044,
0.0*
4,1,15,.00044,-.00398,
.000208,-.003999,
-.000025,-.004004,
-.000258,-.003996,
-.00044,-.00398,
-.00129,-.00483,
-.001007,-.004897,
-.000721,-.004947,
-.000432,-.004981,
-.000141,-.004997,
.000149,-.004997,
.00044,-.00498,
.000729,-.004946,
.001015,-.004895,
.00129,-.00483,
.00044,-.00398,
0.0*
4,1,15,-.00398,-.00044,
-.003999,-.000208,
-.004004,.000025,
-.003996,.000258,
-.00398,.00044,
-.00483,.00129,
-.004897,.001007,
-.004947,.000721,
-.004981,.000432,
-.004997,.000141,
-.004997,-.000149,
-.00498,-.00044,
-.004946,-.000729,
-.004895,-.001015,
-.00483,-.00129,
-.00398,-.00044,
0.0*
4,1,15,-.00044,.00398,
-.000208,.003999,
.000025,.004004,
.000258,.003996,
.00044,.00398,
.00129,.00483,
.001007,.004897,
.000721,.004947,
.000432,.004981,
.000141,.004997,
-.000149,.004997,
-.00044,.00498,
-.000729,.004946,
-.001015,.004895,
-.00129,.00483,
-.00044,.00398,
0.0*
%
%ADD11MACRO11*%
%ADD14C,.107*%
%ADD26C,.225*%
%ADD19C,.237*%
%ADD22C,.139*%
%ADD12C,.186*%
%ADD10C,.168*%
%ADD27C,.02*%
%ADD28C,.006*%
%ADD32C,.08506*%
%ADD31C,.08606*%
%ADD30C,.10306*%
%ADD29C,.18206*%
G75*
%LPD*%
G75*
G36*
G01X-149740Y-6000D02*
X795764D01*
Y931197D01*
X-149740D01*
Y-6000D01*
G37*
%LPC*%
G75*
G36*
G01X385Y214096D02*
X225Y214216D01*
G03X-2503Y215452I-4161J-5555D01*
G01X-2561Y215464D01*
X-2694Y215598D01*
X-3701D01*
X-3704D01*
G03X-3937Y215602I-236J-6937D01*
G01X-139803D01*
G02X-140736Y216535I0J933D01*
G01Y338583D01*
G02X-139803Y339516I933J0D01*
G01X-62992D01*
G03X-62759Y339520I-3J6941D01*
G01X-62756D01*
X-61749D01*
X-61616Y339654D01*
X-61558Y339666D01*
G03X-56201Y345023I-1434J6791D01*
G01X-56189Y345081D01*
X-56055Y345214D01*
Y346221D01*
Y346224D01*
G03X-56051Y346457I-6937J236D01*
G01Y503937D01*
G02X-55118Y504870I933J0D01*
G01X-3937D01*
G03X-3704Y504874I-3J6941D01*
G01X-3701D01*
X-2694D01*
X-2560Y505008D01*
X-2502Y505020D01*
G03X610Y506566I-1434J6791D01*
G01X751Y506688D01*
X1250Y506189D01*
Y281234D01*
G02X481Y281079I-400J0D01*
G03Y274039I-8394J-3520D01*
G02X1250Y273884I369J-155D01*
G01Y215250D01*
X385Y214096D01*
G37*
G36*
G01X3000Y209904D02*
X2866Y210037D01*
X2854Y210095D01*
G03X1552Y212909I-6791J-1434D01*
G01X1459Y213029D01*
X2750Y214750D01*
Y506811D01*
X1742Y507818D01*
X1834Y507954D01*
G03X2854Y510376I-5771J3856D01*
G01X2866Y510434D01*
X3000Y510568D01*
Y511578D01*
G03X3004Y511811I-6937J236D01*
G01Y783465D01*
G02X3937Y784398I933J0D01*
G01X74803D01*
G03X75036Y784402I-3J6941D01*
G01X76046D01*
X76179Y784536D01*
X76237Y784548D01*
G03X81594Y789905I-1434J6791D01*
G01X81606Y789963D01*
X81740Y790096D01*
Y791106D01*
G03X81744Y791339I-6937J236D01*
G01Y921260D01*
G02X82677Y922193I933J0D01*
G01X755906D01*
G02X756839Y921260I0J-933D01*
G01Y821457D01*
G03X763780Y814516I6941J0D01*
G01X767612D01*
X767616Y814520D01*
X773015D01*
Y792173D01*
X771286D01*
X771282Y792177D01*
X765945D01*
G03Y778689I0J-6744D01*
G01X772462D01*
X772466Y778693D01*
X773015D01*
Y740602D01*
X763780D01*
G03X756839Y733661I0J-6941D01*
G01Y663976D01*
G03X763780Y657035I6941J0D01*
G01X765572D01*
X765576Y657039D01*
X773015D01*
Y382724D01*
X770786D01*
X770782Y382728D01*
X765945D01*
G03Y369240I0J-6744D01*
G01X770062D01*
X770066Y369244D01*
X773015D01*
Y331150D01*
X767436D01*
X767432Y331154D01*
X763780D01*
G03X763547Y331150I3J-6941D01*
G01X762537D01*
X762404Y331016D01*
X762346Y331004D01*
G03X756989Y325647I1434J-6791D01*
G01X756977Y325589D01*
X756843Y325456D01*
Y324446D01*
G03X756839Y324213I6937J-236D01*
G01Y3937D01*
G02X755906Y3004I-933J0D01*
G01X3937D01*
G02X3004Y3937I0J933D01*
G01Y208661D01*
G03X3000Y208894I-6941J-3D01*
G01Y209904D01*
G37*
%LPD*%
G75*
G36*
G01X708866Y31408D02*
X708859Y31414D01*
X708852Y31421D01*
G02X708179Y32132I7684J7948D01*
G01X708148Y32166D01*
X708120Y32201D01*
G02X706495Y34742I8414J7171D01*
G01X706486Y34761D01*
X706480Y34776D01*
G02X705946Y36193I10054J4598D01*
G01X705945Y36197D01*
X705944Y36202D01*
G02X705542Y38197I10590J3172D01*
G01X705541Y38207D01*
X705540Y38220D01*
G02X706596Y44211I10995J1151D01*
G01X706602Y44223D01*
G02X708278Y46721I9933J-4853D01*
G01X708318Y46768D01*
X708364Y46816D01*
G02X710669Y48740I8171J-7446D01*
G01X710671Y48742D01*
G02X712010Y49457I5865J-9372D01*
G01X712040Y49471D01*
X712070Y49483D01*
G02X712988Y49841I4472J-10110D01*
G01X712996Y49843D01*
G02X720074I3539J-10473D01*
G01X720082Y49841D01*
G02X721000Y49483I-3554J-10468D01*
G01X721030Y49471D01*
X721060Y49457D01*
G02X722399Y48742I-4526J-10087D01*
G01X722401Y48740D01*
G02X724706Y46816I-5866J-9370D01*
G01X724752Y46768D01*
X724792Y46721D01*
G02X726468Y44223I-8257J-7351D01*
G01X726474Y44211D01*
G02X727530Y38220I-9939J-4840D01*
G01X727529Y38207D01*
X727528Y38197D01*
G02X727126Y36202I-10992J1177D01*
G01X727125Y36197D01*
X727124Y36193D01*
G02X726590Y34776I-10588J3181D01*
G01X726584Y34761D01*
X726575Y34742D01*
G02X724950Y32201I-10039J4630D01*
G01X724922Y32166D01*
X724891Y32132D01*
G02X724218Y31421I-8357J7237D01*
G01X724211Y31414D01*
X724204Y31408D01*
G02X708866I-7669J7962D01*
G37*
G36*
G01X85118Y394516D02*
Y401972D01*
X85111Y401998D01*
G02Y402768I1452J385D01*
G01X85118Y402794D01*
Y417411D01*
X85107Y417443D01*
G02Y418443I1416J500D01*
G01X85118Y418475D01*
Y420122D01*
X85065Y420179D01*
G02Y423159I1622J1490D01*
G01X85118Y423216D01*
Y425409D01*
X85104Y425444D01*
G02Y426530I1401J543D01*
G01X85118Y426565D01*
Y432167D01*
X85059Y432226D01*
G02Y435340I1557J1557D01*
G01X85118Y435399D01*
Y439679D01*
X85049Y439738D01*
G02Y443064I1444J1663D01*
G01X85118Y443123D01*
Y445276D01*
X85112Y445301D01*
G02Y446037I1456J368D01*
G01X85118Y446062D01*
Y465199D01*
X82323Y467998D01*
X82278Y468013D01*
G02X81335Y468957I481J1423D01*
G01X81320Y469002D01*
X78722Y471603D01*
X78624Y471590D01*
G02X76933Y473283I-203J1488D01*
G01X76947Y473381D01*
X74739Y475592D01*
X74667Y475598D01*
G02X73309Y476958I138J1496D01*
G01X73303Y477030D01*
X70808Y479528D01*
X70735Y479535D01*
G02X69372Y480900I133J1496D01*
G01X69365Y480973D01*
X68589Y481750D01*
X66289D01*
X60789Y487250D01*
X25389D01*
X23150Y489489D01*
Y501111D01*
X25489Y503450D01*
X76498D01*
X93697Y486251D01*
X93825Y486315D01*
G02X95837Y484303I665J-1347D01*
G01X95773Y484175D01*
X96048Y483900D01*
X158633D01*
X159939Y485206D01*
X159951Y485265D01*
G02X161126Y486440I1472J-297D01*
G01X161185Y486452D01*
X163876Y489143D01*
X163888Y489202D01*
G02X165063Y490377I1472J-297D01*
G01X165122Y490389D01*
X167813Y493080D01*
X167825Y493139D01*
G02X169000Y494314I1472J-297D01*
G01X169059Y494326D01*
X169161Y494428D01*
X177220D01*
X177269Y494460D01*
G02X178899I815J-1262D01*
G01X178948Y494428D01*
X213042D01*
X222680Y484790D01*
X296727D01*
X310648Y470869D01*
Y457923D01*
X304521Y451796D01*
X300740D01*
X295244Y457292D01*
Y468773D01*
X289153Y474864D01*
X219949D01*
X211436Y483377D01*
Y483395D01*
X210435Y484396D01*
X175527D01*
X175477Y484272D01*
G02X174463Y483385I-1391J567D01*
G01X174410Y483371D01*
X151172Y460133D01*
X142715D01*
X142664Y460099D01*
G02X140990I-837J1247D01*
G01X140939Y460133D01*
X138689D01*
X138638Y460099D01*
G02X136964I-837J1247D01*
G01X136913Y460133D01*
X134586D01*
X132572Y458119D01*
Y423676D01*
X133023Y423225D01*
X133154Y423295D01*
G02X135187Y421262I710J-1323D01*
G01X135117Y421131D01*
X137010Y419238D01*
X137149Y419344D01*
G02X139254Y417239I912J-1193D01*
G01X139148Y417100D01*
X140897Y415351D01*
X141028Y415421D01*
G02X143061Y413388I710J-1323D01*
G01X142991Y413257D01*
X143365Y412883D01*
X147530D01*
X148984Y411429D01*
X149106Y411478D01*
G02X151058Y409526I557J-1395D01*
G01X151009Y409404D01*
X152657Y407756D01*
X152651Y394290D01*
X148011Y389650D01*
X89748D01*
X86483Y392915D01*
X86416Y392924D01*
G02X85118Y394516I200J1489D01*
G37*
G54D32*
X144843Y812994D03*
Y860234D03*
G54D31*
X54724Y557087D03*
Y620079D03*
Y675197D03*
Y738189D03*
X144843Y798779D03*
Y874449D03*
G54D30*
X-33503Y269685D03*
G54D29*
X-59094Y277559D03*
%LPC*%
G75*
G36*
G01X151157Y407134D02*
X151151Y394912D01*
X147389Y391150D01*
X90370D01*
X87900Y393620D01*
X87963Y393749D01*
G03X86794Y395904I-1347J664D01*
G01X86618Y395925D01*
Y400872D01*
X86788Y400898D01*
G03Y403868I-225J1485D01*
G01X86618Y403894D01*
Y416435D01*
X86783Y416464D01*
G03Y419422I-260J1479D01*
G01X86618Y419451D01*
Y424480D01*
X86781Y424511D01*
G03Y427463I-276J1476D01*
G01X86618Y427494D01*
Y432271D01*
X86794Y432292D01*
G03Y435274I-178J1491D01*
G01X86618Y435295D01*
Y439895D01*
X86780Y439927D01*
G03Y442875I-287J1474D01*
G01X86618Y442907D01*
Y444158D01*
X86789Y444183D01*
G03Y447155I-221J1486D01*
G01X86618Y447180D01*
Y465819D01*
X83943Y468498D01*
X84028Y468633D01*
G03X81958Y470706I-1269J803D01*
G01X81822Y470621D01*
X79849Y472598D01*
X79877Y472708D01*
G03X78053Y474534I-1456J370D01*
G01X77943Y474506D01*
X76111Y476340D01*
X76170Y476466D01*
G03X74179Y478459I-1365J628D01*
G01X74053Y478402D01*
X72176Y480280D01*
X72234Y480407D01*
G03X70246Y482398I-1366J624D01*
G01X70119Y482340D01*
X69211Y483250D01*
X66911D01*
X61411Y488750D01*
X26011D01*
X24650Y490111D01*
Y500489D01*
X26111Y501950D01*
X75876D01*
X92993Y484833D01*
X93002Y484767D01*
G03X94289Y483480I1488J201D01*
G01X94355Y483471D01*
X95426Y482400D01*
X155896D01*
G02X156235Y481788I0J-400D01*
G03X156052Y481359I1273J-797D01*
G01X156038Y481305D01*
X153311Y478578D01*
X153252Y478566D01*
G03X152077Y477391I297J-1472D01*
G01X152065Y477332D01*
X148779Y474046D01*
X146889D01*
X146829Y474118D01*
G03X144521I-1154J-961D01*
G01X144461Y474046D01*
X139015D01*
X138955Y474118D01*
G03X136647I-1154J-961D01*
G01X136587Y474046D01*
X131141D01*
X131081Y474118D01*
G03X128773I-1154J-961D01*
G01X128713Y474046D01*
X127980D01*
X106754Y452820D01*
Y431140D01*
X110532Y427362D01*
X131072D01*
Y423054D01*
X132377Y421749D01*
X132389Y421688D01*
G03X133580Y420497I1475J284D01*
G01X133641Y420485D01*
X136817Y417309D01*
X136827Y417294D01*
G03X137204Y416917I1234J857D01*
G01X137219Y416907D01*
X140251Y413875D01*
X140263Y413814D01*
G03X141454Y412623I1475J284D01*
G01X141515Y412611D01*
X142743Y411383D01*
X146908D01*
X148160Y410131D01*
X148161Y410051D01*
G03X149631Y408581I1502J32D01*
G01X149711Y408580D01*
X151157Y407134D01*
G37*
G36*
G01X111154Y428862D02*
X108254Y431762D01*
Y452198D01*
X128227Y472171D01*
G02X128808Y472155I283J-283D01*
G03X131248Y472441I1119J1002D01*
G01X131304Y472546D01*
X136424D01*
X136480Y472441D01*
G03X139122I1321J716D01*
G01X139178Y472546D01*
X144298D01*
X144354Y472441D01*
G03X146996I1321J716D01*
G01X147052Y472546D01*
X149401D01*
X152701Y475846D01*
X152832Y475774D01*
G03X154869Y477811I717J1320D01*
G01X154797Y477942D01*
X156622Y479767D01*
X156755Y479690D01*
G03X158808Y481743I753J1300D01*
G01X158731Y481876D01*
X159255Y482400D01*
X159415D01*
X159854Y482839D01*
Y482999D01*
X160575Y483720D01*
X160706Y483648D01*
G03X162743Y485685I717J1320D01*
G01X162671Y485816D01*
X164512Y487657D01*
X164643Y487585D01*
G03X166680Y489622I717J1320D01*
G01X166608Y489753D01*
X168449Y491594D01*
X168580Y491522D01*
G03X170796Y492741I717J1320D01*
G01X170808Y492928D01*
X176599D01*
X176640Y492783D01*
G03X179528I1444J415D01*
G01X179569Y492928D01*
X212420D01*
X222058Y483290D01*
X296105D01*
X309148Y470247D01*
Y458545D01*
X303899Y453296D01*
X301362D01*
X296744Y457914D01*
Y469395D01*
X289775Y476364D01*
X228097D01*
X228093D01*
G03X227909I-92J-2300D01*
G01X227905D01*
X220571D01*
X212936Y483999D01*
Y484017D01*
X211057Y485896D01*
X175156D01*
X175099Y485948D01*
G03X172789Y484082I-1013J-1109D01*
G01X172866Y483949D01*
X150550Y461633D01*
X143309D01*
X143266Y461776D01*
G03X140388I-1439J-430D01*
G01X140345Y461633D01*
X139283D01*
X139240Y461776D01*
G03X136362I-1439J-430D01*
G01X136319Y461633D01*
X133964D01*
X131072Y458741D01*
Y428862D01*
X111154D01*
G37*
%LPD*%
G75*
G54D16*
X8789Y376072D03*
X6944Y414616D03*
X6855Y436844D03*
X6750Y425868D03*
X7180Y449205D03*
X64055Y389700D03*
X33722Y401639D03*
X74544Y414071D03*
X70779Y402387D03*
X79016Y410283D03*
X35738Y406956D03*
X14422Y411528D03*
X14657Y416838D03*
X10615Y411073D03*
X26551Y394546D03*
X30232Y416556D03*
X23922Y415548D03*
X35994Y410146D03*
X43719Y414419D03*
X32141Y407501D03*
X31808Y410684D03*
X18448Y402542D03*
X74817Y409752D03*
X26972Y399588D03*
X70882Y409794D03*
X66938Y410045D03*
X78939Y414083D03*
X18448Y406788D03*
X53976Y389814D03*
X74894Y398251D03*
X62031Y399713D03*
X70775Y398396D03*
X70845Y405839D03*
X70952Y414050D03*
X54515Y396433D03*
X54463Y386651D03*
X70865Y390502D03*
X74702Y394300D03*
X74869Y406315D03*
X78300Y386505D03*
X64948Y386626D03*
X78362Y398337D03*
X77963Y381183D03*
X70888Y394222D03*
X66931Y484968D03*
X78798Y433983D03*
X17072Y435057D03*
X74836Y453477D03*
X59980Y482517D03*
X78754Y449904D03*
X67112Y481066D03*
X70488Y465291D03*
X74450Y457429D03*
X70713Y461504D03*
X36237Y441728D03*
X70908Y457771D03*
X70898Y418271D03*
X61038Y424878D03*
X74726Y425594D03*
X59209Y438908D03*
X46853Y441796D03*
X78561Y421756D03*
X70809Y438057D03*
X43659Y432766D03*
X43088Y438073D03*
X45486Y456341D03*
X38566Y451290D03*
X42312Y463368D03*
X74780Y429794D03*
X24357Y423051D03*
X37988Y438328D03*
X19757Y418538D03*
X29472Y428016D03*
X78738Y429679D03*
X11964Y421332D03*
X52476Y439395D03*
X13062Y429279D03*
X74656Y421838D03*
X17936Y431103D03*
X14206Y433632D03*
X15424Y422722D03*
X70857Y433857D03*
X19015Y426461D03*
X14147Y438989D03*
X74752Y437655D03*
X74437Y473159D03*
X15872Y441916D03*
X74460Y461287D03*
X78793Y445704D03*
X70868Y477094D03*
X23748Y436249D03*
X26611Y441743D03*
X70909Y469595D03*
X30513Y437850D03*
X74702Y469183D03*
X37420Y461517D03*
X31517Y445328D03*
X70868Y473157D03*
X28472Y447107D03*
X48298Y454813D03*
X70602Y453533D03*
X79050Y457367D03*
X74805Y481031D03*
X66991Y476766D03*
X62798Y461555D03*
X74451Y465323D03*
X79094Y441620D03*
X74801Y433368D03*
X70869Y421840D03*
X70759Y449277D03*
X74805Y477094D03*
X70868Y481031D03*
X74598Y485021D03*
X78421Y473078D03*
X74695Y449260D03*
X59063Y485583D03*
X79134Y461339D03*
X78742Y488905D03*
X66961Y488885D03*
X74805Y492842D03*
X74870Y488789D03*
X69523Y567387D03*
X69555Y564187D03*
X69569Y594959D03*
X69520Y560987D03*
X68421Y570392D03*
X69323Y579887D03*
X69518Y604727D03*
X69599Y601527D03*
X69569Y598159D03*
X69388Y576660D03*
X69450Y573460D03*
X69569Y608021D03*
X69496Y611417D03*
X69661Y591387D03*
X66579Y592250D03*
X63125Y592801D03*
X62681Y589462D03*
X69451Y684303D03*
Y681103D03*
X68928Y687846D03*
X69316Y697605D03*
X69451Y691003D03*
X69474Y694403D03*
X69523Y718313D03*
Y715113D03*
X69472Y729385D03*
X69548Y726185D03*
X69558Y711913D03*
X68620Y722610D03*
X106419Y310245D03*
X126184Y310860D03*
X93200Y308800D03*
X102364Y402287D03*
X106301Y398350D03*
Y402287D03*
X102364Y398350D03*
X110238Y402287D03*
X114175D03*
X110238Y398350D03*
X114175D03*
X85721Y385798D03*
X149362Y413951D03*
X149498Y406396D03*
X145795Y410173D03*
X149431Y394402D03*
X149783Y390487D03*
X110238Y410161D03*
X141738Y414098D03*
X133863Y413773D03*
X114175Y414098D03*
X122053D03*
X125990Y410161D03*
X94579Y406324D03*
X118130Y398511D03*
X98427Y410161D03*
X90553Y414098D03*
X86563Y402383D03*
X133964Y394555D03*
X102555Y394412D03*
X86616Y394413D03*
X86463Y390483D03*
X114175Y406224D03*
X126063Y406183D03*
X141738Y406224D03*
X106301D03*
X149663Y410083D03*
X82459Y413976D03*
X90566Y394383D03*
X82663Y402406D03*
X133864Y402287D03*
X86772Y414047D03*
X122053Y402287D03*
X133864Y398350D03*
X137801D03*
X122053D03*
X137801Y402287D03*
X125990D03*
Y398350D03*
X129927Y402287D03*
Y398350D03*
X82663Y398383D03*
X141738Y402287D03*
Y398350D03*
X145865Y402287D03*
Y398350D03*
X149488Y402114D03*
X149583Y398383D03*
X90359Y469275D03*
X102684Y445671D03*
X106263Y437583D03*
X102364Y429846D03*
X98363Y421883D03*
X94263Y418129D03*
X106210Y421976D03*
X110332Y425814D03*
X86493Y441401D03*
X86616Y433783D03*
X86687Y421669D03*
X117951Y437592D03*
X114175Y445598D03*
X110263Y441683D03*
X118189Y445711D03*
X125990Y445598D03*
X110238Y437720D03*
X125990D03*
X110222Y417989D03*
X106341Y426062D03*
X82564Y449659D03*
X145663Y441483D03*
X98288Y441609D03*
X149612Y429846D03*
X149594Y480923D03*
X94518Y449186D03*
X86768Y449383D03*
X98427Y484968D03*
Y481031D03*
X102364D03*
Y484968D03*
X106301D03*
Y481031D03*
X114175Y484968D03*
Y481031D03*
X122053Y484968D03*
Y481031D03*
X125990Y484968D03*
Y481031D03*
X145567Y453547D03*
X145763Y449583D03*
X149576Y465497D03*
X98597Y457291D03*
X94490Y429846D03*
X90463Y425983D03*
X90480Y437608D03*
X82562Y425980D03*
X86505Y425987D03*
X90380Y429650D03*
X130080Y457372D03*
X94490Y437720D03*
X82681Y430041D03*
X141827Y461346D03*
X98334Y429754D03*
X98427Y437720D03*
X94369Y425977D03*
X82677Y433595D03*
X149563Y469220D03*
X94490Y433783D03*
X141738Y481031D03*
X82663Y457486D03*
X141738Y484968D03*
X98433Y449125D03*
X137801Y481031D03*
X102600Y425983D03*
X137801Y484968D03*
X94554Y421911D03*
X133864Y481031D03*
X149612Y437720D03*
X94414Y445605D03*
X133864Y484968D03*
X86663Y429536D03*
X82542Y445403D03*
X98427Y433783D03*
X86568Y445669D03*
X90426Y449431D03*
X90563Y417983D03*
X145675Y425909D03*
X82573Y441360D03*
X145675Y437720D03*
X98280Y445405D03*
X90426Y441880D03*
X145675Y481031D03*
Y484968D03*
X145737Y418077D03*
X145675Y473157D03*
Y465283D03*
X149719Y457328D03*
X129927Y473157D03*
Y465283D03*
X137801Y461346D03*
Y457409D03*
X114175Y473157D03*
X122053Y469220D03*
X110263Y469083D03*
X122053Y473157D03*
X90350Y473069D03*
X82679Y477094D03*
X90662Y461604D03*
X106263Y453483D03*
X106449Y465157D03*
X122053Y445598D03*
X126180Y418224D03*
X137801Y437720D03*
X137767Y425993D03*
X129927Y445598D03*
X141738Y449535D03*
X133864Y421972D03*
Y429846D03*
X98533Y418180D03*
X118134Y449362D03*
X106363Y441583D03*
X110238Y445598D03*
X110289Y422113D03*
X122053Y437720D03*
X114175D03*
X94661Y441681D03*
X106263Y433683D03*
X90544Y433408D03*
X90408Y421930D03*
X129927Y437720D03*
X141738Y429846D03*
X86663Y453583D03*
X82732Y453139D03*
X102227Y473344D03*
X145675Y469220D03*
X90376Y476918D03*
X110238Y477094D03*
X141738D03*
X137801Y473157D03*
X98427Y469046D03*
X106301Y469220D03*
X114175D03*
X126057Y469287D03*
X129927Y469220D03*
X137801D03*
X122053Y465283D03*
X133864D03*
X106301Y461346D03*
X122113Y457535D03*
X129963Y461283D03*
X110263Y457283D03*
X122158Y453388D03*
X125990Y477094D03*
X137801Y449535D03*
X149612Y425909D03*
X82535Y461227D03*
X83021Y473118D03*
X141595Y421932D03*
X141775Y426153D03*
X86735Y461382D03*
X141763Y437883D03*
X86937Y477160D03*
X141682Y417902D03*
X82759Y469436D03*
X145663Y445583D03*
X145675Y429846D03*
X142008Y457429D03*
X141863Y445583D03*
X86959Y469276D03*
X137570Y421843D03*
X145561Y421879D03*
X90965Y465270D03*
X129927Y481031D03*
Y484968D03*
X110238Y481031D03*
Y484968D03*
X94490Y481031D03*
X86663Y457283D03*
X94490Y484968D03*
X86765Y465205D03*
X138061Y418151D03*
X145675Y433783D03*
X82763Y417750D03*
X86523Y417943D03*
X94844Y469182D03*
X102469Y469134D03*
X106149Y457371D03*
X141649Y453189D03*
X149620Y485149D03*
X98682Y461441D03*
X94092Y492819D03*
X141738Y488905D03*
X110238D03*
X125990D03*
X94377Y489070D03*
X118004Y488825D03*
X133864Y488905D03*
X149612D03*
X102308Y488978D03*
X86616Y488905D03*
X91852Y563129D03*
X91156Y572112D03*
X90823Y581387D03*
X91343Y598284D03*
X91023Y606587D03*
X90923Y616187D03*
X91198Y595087D03*
X91123Y591887D03*
X91223Y588487D03*
X159768Y238444D03*
X160004Y233894D03*
X214660Y362600D03*
X176751Y387090D03*
X157251Y414149D03*
X161477Y394511D03*
X180991Y398678D03*
X180809Y414170D03*
X179225Y403667D03*
X203410Y394323D03*
X182378Y390377D03*
X157574Y394185D03*
X161241Y398226D03*
X161277Y414114D03*
X174124Y402624D03*
X161213Y390551D03*
X169503Y386977D03*
X153587Y406496D03*
X157554Y402251D03*
X157698Y406313D03*
X161475Y410299D03*
X165266Y409882D03*
X165337Y414489D03*
X153528Y410052D03*
X165455Y398256D03*
X165229Y402019D03*
X157411Y398513D03*
X169113Y398299D03*
X178031Y390023D03*
X153549Y429846D03*
X165621Y418066D03*
X153549Y425909D03*
X161746Y421972D03*
X177182Y467018D03*
X175477Y472360D03*
X176815Y479061D03*
X161473Y457213D03*
X165360Y477094D03*
X153549Y437720D03*
X157560Y445484D03*
X153549Y449535D03*
X174859Y469220D03*
X157322Y453385D03*
X165317Y461561D03*
X165360Y473157D03*
X161455Y453385D03*
X177763Y486293D03*
X153463Y453383D03*
X157411Y469344D03*
X161423Y477094D03*
X157486Y461346D03*
X153690Y469111D03*
X165411Y429590D03*
X175161Y434723D03*
X161423Y445598D03*
X153549Y421972D03*
X161423Y484968D03*
Y481031D03*
X157486Y473157D03*
X165360Y469220D03*
X153549Y477094D03*
X173234Y465283D03*
Y453472D03*
X174086Y484839D03*
X175150Y476294D03*
X174351Y429014D03*
X161423Y437720D03*
X153549Y433783D03*
X161363Y425780D03*
X173234Y437720D03*
X173155Y417978D03*
X153422Y441722D03*
X161423Y449430D03*
X153549Y473157D03*
X161670Y418161D03*
X176662Y418122D03*
X153201Y418097D03*
X157401Y418143D03*
X157463Y421883D03*
X157486Y425909D03*
X173458Y457178D03*
X178053Y474260D03*
X174601Y481467D03*
X165319Y453134D03*
X165353Y480812D03*
X157486Y433783D03*
X165360Y421972D03*
X153646Y457393D03*
X161294Y461561D03*
X165363Y425783D03*
X157393Y457572D03*
X165217Y457361D03*
X165355Y433382D03*
X161423Y473157D03*
X165355Y437582D03*
X165360Y445598D03*
X157411Y449556D03*
X169157Y445598D03*
X157508Y480990D03*
X165288Y449306D03*
X157486Y484968D03*
X153601Y480894D03*
X153586Y485118D03*
X161423Y433783D03*
X174475Y488016D03*
X178084Y493198D03*
X157486Y488905D03*
X165360D03*
X169297Y492842D03*
X161423D03*
X159589Y817543D03*
X157422Y825918D03*
X158725Y835536D03*
X159688Y832484D03*
X159431Y838974D03*
X159688Y829234D03*
X159137Y820712D03*
X160735Y857183D03*
X154730Y847010D03*
X159688Y851564D03*
X159560Y842172D03*
X159426Y848357D03*
X651000Y467700D03*
X646163Y482677D03*
X643296Y477617D03*
X643914Y470592D03*
X648652Y470028D03*
X654990Y463513D03*
X658399Y460842D03*
X659485Y455066D03*
X666818Y452921D03*
X710645Y447266D03*
X678767Y447136D03*
X672583Y467901D03*
X667831Y479556D03*
X662166Y456914D03*
X661760Y460089D03*
X646246Y475961D03*
X646794Y472634D03*
X682915Y467823D03*
X708059Y449951D03*
X671145Y454348D03*
X658195Y464248D03*
X653351Y470098D03*
X650837Y472421D03*
X646251Y479161D03*
X675745Y448189D03*
X685815Y496140D03*
X689996Y496274D03*
X694169Y496394D03*
X698475Y496387D03*
X702670Y496148D03*
X707296Y496348D03*
X716700Y445400D03*
X742200Y472500D03*
X724300Y454000D03*
X719100Y478900D03*
X744986Y481255D03*
X749974Y477780D03*
X749628Y471196D03*
X739751Y469686D03*
X735295Y463720D03*
X738636Y457903D03*
X731780Y452531D03*
X729478Y459116D03*
X721600Y451000D03*
X719700Y485600D03*
X735191Y453967D03*
X735231Y457167D03*
X746845Y476389D03*
Y473189D03*
X717993Y451389D03*
X731751Y464398D03*
X735259Y469898D03*
X721445Y455789D03*
X726589Y460909D03*
X743520Y478297D03*
X738745Y472789D03*
X713845Y447289D03*
G54D15*
X9243Y334400D03*
X8788Y453864D03*
X43980Y86200D03*
X68000Y87750D03*
X42700Y110500D03*
X67300Y107200D03*
X63100Y107300D03*
X48100Y133900D03*
X59200Y95573D03*
X51800Y93500D03*
X79600Y91500D03*
X51900Y89900D03*
X79500Y85700D03*
X77200Y95500D03*
X76250Y148850D03*
X70200Y199300D03*
X47900Y145500D03*
X48100Y153800D03*
X43800Y204800D03*
X38800Y194300D03*
X38700Y199700D03*
X73700D03*
X49500Y169300D03*
X61751Y181464D03*
X44100Y200600D03*
X49286Y203671D03*
X69000Y202700D03*
X77200Y189000D03*
X60200Y193550D03*
X29600Y200100D03*
X26100Y187300D03*
X39800Y172900D03*
X27800Y191100D03*
X74700Y191700D03*
X70675Y145000D03*
X50500Y243100D03*
X70636Y272953D03*
X79189Y235119D03*
X43900Y209000D03*
X72001Y265901D03*
X69400Y207400D03*
X76019Y222534D03*
X43181Y278603D03*
X39563Y307968D03*
X21876Y282289D03*
X41418Y287473D03*
X29700Y355000D03*
X27284Y358500D03*
X67527Y381818D03*
X43569Y379314D03*
X65605Y367307D03*
X24315Y472668D03*
X47307Y465104D03*
X29064Y471345D03*
X55295Y479672D03*
X20715Y485712D03*
X20276Y477090D03*
X20928Y453864D03*
X21300Y468000D03*
X51383Y514037D03*
X63862Y512438D03*
X73542Y514340D03*
X37200Y513500D03*
X32026Y516764D03*
X60800Y505200D03*
X56121Y494271D03*
X21090Y497108D03*
X54659Y513125D03*
X67140Y511501D03*
X50893Y534434D03*
X66300Y548000D03*
X67244Y535455D03*
X72677Y528615D03*
X69220Y614992D03*
X47000Y645300D03*
X69911Y676938D03*
X73900Y664900D03*
X77000Y646200D03*
X72930Y645818D03*
X67257Y643668D03*
X47100Y746000D03*
X69217Y732676D03*
X73325Y760926D03*
X67809Y758190D03*
X65447Y711413D03*
X62066Y711051D03*
X65356Y707010D03*
X61193Y706973D03*
X73282Y778907D03*
X82400Y89500D03*
X132500Y124600D03*
X83800Y188800D03*
X111482Y202800D03*
X113815Y194333D03*
X122400Y199000D03*
X80685Y192398D03*
X84641Y204036D03*
X79900Y148700D03*
X103300Y160900D03*
X112000Y160700D03*
X119900Y162200D03*
X125300Y162300D03*
X122100Y203300D03*
X96900Y189286D03*
X107771Y182699D03*
X145400Y161955D03*
X114700Y157000D03*
X107672Y156597D03*
X98700Y156200D03*
X122200Y156700D03*
X80207Y139965D03*
X81200Y176000D03*
X93303Y154970D03*
X144950Y177338D03*
X85713Y151540D03*
X84900Y145300D03*
X87227Y242891D03*
X87263Y264658D03*
X90652Y265960D03*
X87698Y246708D03*
X94051Y265872D03*
X91230Y247047D03*
X91819Y250396D03*
X94793Y252595D03*
X98211Y252758D03*
X142933Y251431D03*
X132651Y255357D03*
X138228Y260175D03*
X124933Y270414D03*
X136427Y251413D03*
X124874Y273953D03*
X137809Y247647D03*
X135592Y257933D03*
X116566Y254205D03*
X114229Y270684D03*
X119242Y252107D03*
X112042Y275903D03*
X121685Y249741D03*
X121741Y246341D03*
X118219Y274497D03*
X122572Y258147D03*
X121599Y274869D03*
X130567Y258051D03*
X113558Y261260D03*
X111008Y242830D03*
X106381Y259865D03*
X106504Y243329D03*
X103610Y268626D03*
X102713Y242975D03*
X103003Y260260D03*
X108652Y247260D03*
X107887Y266647D03*
X101242Y265901D03*
X100415Y246679D03*
X126611Y258265D03*
X84863Y229783D03*
X134529Y264470D03*
X137190Y266587D03*
X131901Y267444D03*
X132163Y271041D03*
X137690Y273752D03*
X110610Y206436D03*
X125600Y221200D03*
X113863Y228669D03*
X102559Y228575D03*
X97885Y228339D03*
X147013Y225483D03*
X122000Y207300D03*
X94600Y206900D03*
X94548Y211258D03*
X92682Y331571D03*
X140103Y328216D03*
X117460Y335158D03*
X128964Y339470D03*
X148102Y338366D03*
X119603Y285731D03*
X124478Y280855D03*
X95202Y290958D03*
X98565Y290455D03*
X102107Y290439D03*
X105603Y291092D03*
X95146Y279609D03*
X110808Y291075D03*
X98546Y279609D03*
X114915Y290203D03*
X104413Y278608D03*
X117027Y278475D03*
X148834Y284832D03*
X107750Y277953D03*
X128918Y307533D03*
X135308Y276806D03*
X139784Y276432D03*
X142241Y278783D03*
X121477Y314973D03*
X135613Y308903D03*
X84200Y380000D03*
X118744Y525279D03*
X140399Y525238D03*
X129199Y525271D03*
X107103Y525057D03*
X95599Y525026D03*
X84799Y524898D03*
X90878Y585185D03*
X85654Y659044D03*
X83960Y632636D03*
X90681Y690157D03*
X90174Y678675D03*
X85600Y647837D03*
X83500Y653600D03*
Y640044D03*
X84900Y747900D03*
X93840Y699686D03*
X90814Y734451D03*
X91027Y724985D03*
X91094Y715818D03*
X84703Y758885D03*
X84182Y764879D03*
X90746Y712435D03*
X90947Y709040D03*
X91003Y705214D03*
X91130Y701741D03*
X85300Y755100D03*
X85000Y775900D03*
X84100Y769000D03*
X220131Y58163D03*
X197900Y82000D03*
X201237Y106350D03*
X210356Y99104D03*
X210680Y84396D03*
X201614Y89932D03*
X212028Y93512D03*
X212800Y125800D03*
X182400Y128300D03*
X175598Y128436D03*
X220100Y123600D03*
X166700Y128800D03*
X172200Y128300D03*
X179000D03*
X205628Y89404D03*
X152350Y131084D03*
X204849Y106438D03*
X200100Y101200D03*
X170302Y147100D03*
X158100Y166800D03*
X160311Y141680D03*
X219548Y174651D03*
X189600Y166700D03*
X189700Y170200D03*
X190018Y173586D03*
X188961Y162715D03*
X211700Y181600D03*
X208200Y153500D03*
X203900D03*
X200100Y146500D03*
Y150400D03*
X199100Y153800D03*
X194800D03*
X174339Y151172D03*
X178400Y152300D03*
X167015Y167633D03*
X163550Y179657D03*
X172645Y179104D03*
X177087Y178920D03*
X152663Y272053D03*
X192284Y258847D03*
X150666Y243134D03*
X195698Y259749D03*
X196365Y256414D03*
X168324Y246397D03*
X171762Y258345D03*
X167894Y243024D03*
X167760Y239626D03*
X156800Y230500D03*
X152663Y267791D03*
X216335Y218212D03*
X196344Y237383D03*
X196078Y248183D03*
X196021Y244556D03*
X196151Y240983D03*
X151519Y250193D03*
X180641Y231683D03*
X186319Y268076D03*
X184188Y340638D03*
X162135Y332650D03*
X185042Y286734D03*
X167051Y293752D03*
X188273Y285674D03*
X187118Y281963D03*
X163142Y294193D03*
X183466Y294017D03*
X152580Y285530D03*
X172818Y288683D03*
X216178Y411331D03*
X219144Y414536D03*
X195307Y355649D03*
X206775Y348954D03*
X173508Y348462D03*
X177715Y397471D03*
X212500Y395500D03*
X217800Y395900D03*
X200161Y416474D03*
X206142Y413945D03*
X206871Y397177D03*
X210042Y412265D03*
X175767Y380311D03*
X189073Y380379D03*
X185276Y380362D03*
X181242Y380481D03*
X197565Y380257D03*
X203379Y380312D03*
X169600Y380500D03*
X173864Y397677D03*
X181980Y458681D03*
X210772Y431456D03*
X200453Y439066D03*
X203186Y451492D03*
X180445Y422567D03*
X176991Y463723D03*
X184750Y427953D03*
X208947Y443700D03*
X196803Y444462D03*
X201400Y434400D03*
X202764Y444274D03*
X190887Y424438D03*
X174500Y424100D03*
X182060Y443776D03*
X211243Y462005D03*
X203406Y454885D03*
X195038Y477148D03*
X180313Y446694D03*
X176915Y446556D03*
X195400Y452051D03*
X208632Y457048D03*
X181034Y427967D03*
X177700Y427300D03*
X184399Y525203D03*
X195499D03*
X206699D03*
X217899Y525103D03*
X162615Y525220D03*
X173537D03*
X151684Y525258D03*
X210223Y501477D03*
X213500Y503600D03*
X216300Y499600D03*
X193016Y496643D03*
X219492Y517832D03*
X219590Y740816D03*
X181642Y837321D03*
Y827853D03*
X181772Y818429D03*
X159926Y813000D03*
X201663Y827680D03*
X201142Y837191D03*
X181081Y856307D03*
X181124Y847013D03*
X200798Y846849D03*
X266700Y46900D03*
X263000Y47000D03*
X257500Y46900D03*
X253800Y47000D03*
X244900Y47300D03*
X248600Y47200D03*
X235000Y47500D03*
X238700Y47400D03*
X225231Y58420D03*
X254498Y88487D03*
X251687Y98033D03*
X261830Y81230D03*
X241101D03*
X256928Y69301D03*
X241132Y85023D03*
X259815Y94233D03*
X248000Y114500D03*
X242488Y88466D03*
X223948Y174292D03*
X246100Y151300D03*
Y155800D03*
Y160400D03*
X231049Y188760D03*
X251700Y135484D03*
X238614Y217763D03*
X222496Y222320D03*
X223129Y210901D03*
X224664Y293860D03*
X228243Y380358D03*
X231915Y380533D03*
X244928Y367685D03*
X238151Y356092D03*
X228510Y367624D03*
X240715Y380333D03*
X222269Y402278D03*
X228949Y410741D03*
X225421Y410908D03*
X269840Y386256D03*
X239693Y396029D03*
X257500Y399300D03*
X264600Y380500D03*
X270800Y408500D03*
X261300Y402355D03*
X275500Y415400D03*
X264124Y408219D03*
X258267Y408800D03*
X233400Y409700D03*
X255010Y367624D03*
X273554Y386722D03*
X223600Y456200D03*
X269300Y486200D03*
X249600Y432500D03*
X239000Y440300D03*
X244800Y454500D03*
X229600Y460700D03*
X289200Y445100D03*
X252200Y486700D03*
X290300Y462400D03*
X290011Y456234D03*
X289000Y449200D03*
X221035Y453935D03*
X279120Y440440D03*
X276761Y443421D03*
X277575Y449398D03*
X270714Y458323D03*
X263719Y455536D03*
X259779Y456823D03*
X220768Y418393D03*
X260322Y462288D03*
X256852Y465331D03*
X258221Y469246D03*
X235069Y464940D03*
X257184Y421241D03*
X271342Y440630D03*
X235600Y433300D03*
X264775Y459236D03*
X279789Y432846D03*
X285565Y438912D03*
X250400Y473300D03*
X260481Y473769D03*
X253214Y469048D03*
X228400Y486400D03*
X228001Y474064D03*
X226000Y458700D03*
X249845Y469508D03*
X229300Y442500D03*
X225700Y496800D03*
X226115Y507011D03*
X229513Y507141D03*
X232912Y507242D03*
X224515Y532633D03*
X237336Y531828D03*
X236700Y539300D03*
X240400Y534500D03*
X245800D03*
X241300Y539300D03*
X236300Y535600D03*
X243200Y531700D03*
X288586Y493703D03*
X268215Y490733D03*
X251755Y491731D03*
X270700Y495400D03*
X274315Y497133D03*
X283657Y532832D03*
X280259Y532714D03*
X232200Y492100D03*
X231739Y495469D03*
X248286Y489208D03*
X242100Y489000D03*
X268600Y529800D03*
X256300Y531400D03*
X289400Y511700D03*
X243300Y527900D03*
X247256Y529218D03*
X251700Y531500D03*
X268500Y525800D03*
X238118Y492166D03*
X246132Y492160D03*
X289405Y515437D03*
X228500Y498900D03*
X281183Y592936D03*
X223671Y740896D03*
X228249Y761450D03*
X223129Y764830D03*
X236973Y795418D03*
X237950Y774979D03*
X237815Y779065D03*
X226949Y782735D03*
X235169Y791455D03*
X240130Y789012D03*
X277254Y852624D03*
X314000Y405200D03*
X316800Y415900D03*
X299800Y398500D03*
X332600Y400100D03*
X305456Y481787D03*
X335532Y485626D03*
X323215Y485633D03*
X304783Y467192D03*
X301437Y426833D03*
X304200Y432600D03*
X300603Y432406D03*
X309200Y444700D03*
X331800Y440400D03*
X331900Y444600D03*
X356700Y437500D03*
X348800D03*
X341500Y437400D03*
X291300Y468600D03*
X308900Y449100D03*
X327900Y438100D03*
X341430Y459351D03*
X345735Y460843D03*
X349800Y460000D03*
X353698Y460323D03*
X357812Y460406D03*
X297238Y429641D03*
X304550Y424222D03*
X300059Y422844D03*
X318015Y493833D03*
X334315Y496733D03*
X330815Y493433D03*
X327115Y489533D03*
X344815Y494933D03*
X321415Y497133D03*
X304000Y538500D03*
X308800Y540925D03*
X350400Y512000D03*
X335600Y511400D03*
X304700Y509500D03*
X317900Y520100D03*
X314628Y517729D03*
X343905Y519116D03*
X324400Y570500D03*
X362793Y77815D03*
Y126096D03*
X381025Y73748D03*
Y120650D03*
X373496Y140021D03*
X365131Y135484D03*
X413900Y396400D03*
X428343Y463067D03*
X420575Y467336D03*
X382695Y467033D03*
Y471133D03*
X388884Y468631D03*
X387143Y462647D03*
X378700Y437600D03*
X371200Y437800D03*
X363800Y437700D03*
X428616Y429466D03*
X391500Y459000D03*
X399900Y458600D03*
X421273Y439381D03*
X361533Y460222D03*
X365241Y460010D03*
X416588Y467839D03*
X473838Y385675D03*
X474106Y382285D03*
X500526Y394177D03*
X473605Y389068D03*
X499764Y411324D03*
X497279Y382551D03*
X435138Y460661D03*
X457091Y486699D03*
X475600Y462100D03*
X452300Y420900D03*
X458900Y446600D03*
X483100Y449900D03*
X488500Y474200D03*
X450300Y459900D03*
X471300Y482200D03*
X449000Y480000D03*
X438316Y449493D03*
X438294Y453811D03*
X501700Y477200D03*
X471410Y490049D03*
X498994Y488322D03*
X501802Y490240D03*
X494400Y493600D03*
Y497500D03*
X471650Y493916D03*
X494410Y501344D03*
X458713Y518034D03*
X482200Y529100D03*
X484200Y538000D03*
X483800Y545700D03*
X452652Y495705D03*
X465900Y501200D03*
X517041Y388700D03*
X513500Y399060D03*
X520900Y388100D03*
X536928Y411324D03*
X514000Y486293D03*
X508306Y428179D03*
X523462Y423957D03*
X503923Y423910D03*
X536736Y418540D03*
X504500Y479500D03*
X503300Y539700D03*
X529000Y550500D03*
X502318Y535328D03*
X521002Y555911D03*
X525300Y552800D03*
X516900Y561200D03*
X528000Y562900D03*
X512700Y560000D03*
X637200Y393900D03*
X632600Y555200D03*
X636200Y555100D03*
X640100Y550600D03*
X638300Y511800D03*
X641800Y519000D03*
X639500Y521900D03*
X641700Y510300D03*
X662100Y394600D03*
X667979Y486293D03*
X702400Y431500D03*
X698300Y431600D03*
X702000Y485700D03*
X688615Y485133D03*
X693509Y431701D03*
X689111Y431612D03*
X684869Y431611D03*
X680738Y431633D03*
X711409Y467621D03*
X707700Y476500D03*
X707890Y467821D03*
X684259Y476130D03*
X682774Y449737D03*
X667745Y456089D03*
X662604Y463284D03*
X643833Y549325D03*
X702000Y546581D03*
X702400Y550600D03*
X684600Y542100D03*
X682015Y493633D03*
X665499Y556600D03*
X651800Y540295D03*
X711400Y515400D03*
X711900Y521500D03*
X675400Y538100D03*
X662200Y547300D03*
X709600Y524100D03*
X658314Y526697D03*
X672168Y538889D03*
X676115Y542633D03*
X712102Y542133D03*
X707589Y515400D03*
X700900Y539500D03*
X697600Y560000D03*
X701400Y560200D03*
X707391Y564566D03*
X643100Y589900D03*
X700989Y759255D03*
X667982Y739870D03*
X681402Y757754D03*
X663575Y742289D03*
X668987Y731465D03*
X711116Y796516D03*
X702290Y820921D03*
X680480Y773302D03*
X678755Y784815D03*
X676727Y790555D03*
X679630Y795856D03*
X680239Y802378D03*
X682693Y806283D03*
X684732Y810518D03*
X669886Y786112D03*
X666516Y784722D03*
X686308Y834802D03*
X646342Y826469D03*
X685799Y770894D03*
X690211Y827401D03*
X683715Y852233D03*
X710727Y862002D03*
X678351Y854383D03*
X679332Y841866D03*
X681156Y844982D03*
X681542Y848361D03*
X722687Y120650D03*
X727300Y273200D03*
X758200Y338900D03*
X756700Y370600D03*
X762900Y387400D03*
X768000Y457700D03*
X767700Y473300D03*
X719800Y525000D03*
X719866Y528656D03*
X751965Y522097D03*
X747886D03*
X757848Y513543D03*
X752874Y534854D03*
X737297Y517903D03*
X756523Y520272D03*
X749493Y535216D03*
X725100Y519600D03*
X746000Y549700D03*
X726800Y527400D03*
X723538Y526440D03*
X742607Y549481D03*
X752100Y506500D03*
X749500Y508800D03*
X742000Y505000D03*
X762275Y512870D03*
X744073Y522097D03*
X755862Y516303D03*
X756400Y508100D03*
X756272Y534995D03*
X763000Y490800D03*
X725900Y561800D03*
X737400Y576200D03*
X766358Y564600D03*
X727700Y584400D03*
X758400Y568500D03*
X742600Y577100D03*
X756100Y658700D03*
X757600Y639700D03*
X746669Y740179D03*
X743653Y744114D03*
X741453Y748054D03*
X738850Y751989D03*
X734450Y755929D03*
X730967Y759864D03*
X724305Y770450D03*
X723678Y774016D03*
X727477Y775212D03*
X724733Y779559D03*
X730028Y782297D03*
X724859Y784497D03*
X742663Y788885D03*
X729988Y787114D03*
X739510Y795264D03*
X725239Y788970D03*
X745230Y793211D03*
X729486Y791416D03*
X742370Y799077D03*
X725407Y794540D03*
X747659Y796960D03*
X744790Y802781D03*
X749593Y803991D03*
X747556Y808994D03*
X749629Y812608D03*
X722443Y826463D03*
X721704Y829981D03*
X724858Y831254D03*
X723801Y834857D03*
X726332Y837128D03*
X733066Y836450D03*
X721243Y850725D03*
X718263Y863827D03*
X745100Y859405D03*
X721112Y854419D03*
X724093Y840187D03*
X726776Y842277D03*
X733796Y854172D03*
G54D17*
X6614Y553544D03*
X10551Y623622D03*
X6614Y671654D03*
X10551Y741732D03*
X18425Y553544D03*
X32204D03*
X18425Y623622D03*
X32204D03*
X18425Y671654D03*
X32204D03*
X18425Y741732D03*
X32204D03*
G54D13*
X4800Y48600D03*
X5800Y6400D03*
X5000Y71900D03*
Y91900D03*
X5100Y111800D03*
X4900Y130400D03*
X5000Y150500D03*
X5300Y170000D03*
X9151Y473051D03*
X8672Y487593D03*
X7075Y527972D03*
X7927Y509647D03*
X8140Y637282D03*
X8246Y771416D03*
X45700Y61000D03*
X65500Y60800D03*
X75500D03*
X45900Y50000D03*
X65700Y49800D03*
X50800Y39500D03*
X70700Y45800D03*
X55800Y61300D03*
X59900Y40600D03*
X53200Y26300D03*
X50600Y6000D03*
X50500Y67700D03*
X70500Y72000D03*
X60800Y72500D03*
X57200Y175300D03*
X16158Y477255D03*
X33600Y512600D03*
X37329Y524472D03*
X33880Y526500D03*
X33921Y520414D03*
X18809Y491871D03*
X17212Y532250D03*
X18064Y513925D03*
X18277Y641560D03*
X9844Y658803D03*
X19981Y663081D03*
X9631Y753837D03*
X19768Y758115D03*
X18383Y775694D03*
X55459Y780063D03*
X48300Y775300D03*
X87900Y47800D03*
X90900Y42400D03*
X80400Y47800D03*
X124100Y6700D03*
X110800Y48800D03*
X120200Y48400D03*
X98700Y48900D03*
X143900Y38000D03*
X108100Y35300D03*
X146900Y48500D03*
X109700Y6400D03*
X119700Y35400D03*
X139800Y31100D03*
X96300Y6100D03*
X147200Y7300D03*
X108600Y19900D03*
X126500Y20100D03*
X147500Y90200D03*
X142167Y106366D03*
X142101Y98650D03*
X111100Y75500D03*
X100000Y75600D03*
X121700Y75300D03*
X85300Y70200D03*
X126300Y180209D03*
X126700Y173500D03*
X136291Y179968D03*
X136100Y173800D03*
X134200Y217300D03*
X130000Y217200D03*
X134600Y222200D03*
X106051Y767209D03*
X122899Y825236D03*
X112762Y820958D03*
X116188Y771487D03*
X131900Y893200D03*
X120874Y857517D03*
X110737Y853239D03*
X131700Y915700D03*
X89871Y917500D03*
X209100Y51700D03*
X191700Y63300D03*
X209200Y65100D03*
X200700Y51700D03*
X185100Y55900D03*
X208900Y58600D03*
X192000Y55900D03*
X200700Y58300D03*
X184700Y63100D03*
X173200Y10900D03*
X213700Y35200D03*
X186000D03*
X197796Y12653D03*
X160600Y49100D03*
X153200Y48700D03*
X167500Y49000D03*
X160500Y19700D03*
X170400Y31100D03*
X150600Y37800D03*
X154500Y90000D03*
X158000Y79600D03*
X165200Y79500D03*
X163300Y95900D03*
X163500Y105500D03*
X151800Y72400D03*
X209000Y72300D03*
X201500D03*
X177100Y99500D03*
X177200Y104800D03*
X177300Y94200D03*
Y88500D03*
X184700D03*
X190700Y77800D03*
X201200Y65600D03*
X191000Y71300D03*
X184500Y71200D03*
X177400Y71400D03*
X177500Y77900D03*
X183700Y78100D03*
X191500Y88500D03*
X204200Y126700D03*
X206600Y130300D03*
X201900D03*
X207495Y192761D03*
X169800Y155796D03*
X165162Y155909D03*
X169709Y160049D03*
X165388Y160094D03*
X196400Y585300D03*
X179000Y624800D03*
X193600Y702400D03*
X179100Y714600D03*
X202300Y742000D03*
X189273Y902478D03*
X213138Y905780D03*
X218729Y857629D03*
X200460Y913771D03*
X282282Y47189D03*
X286930D03*
X233900Y32500D03*
X252187Y23895D03*
X286651Y14571D03*
X224431Y15210D03*
X248900Y8400D03*
X282444Y106834D03*
X225919Y88394D03*
X225937Y80731D03*
X221710Y80767D03*
X221722Y88431D03*
X230158Y88359D03*
X230123Y80805D03*
X225851Y73774D03*
X221740Y73844D03*
X229870Y73970D03*
X228169Y68374D03*
X224169Y68520D03*
X228728Y96613D03*
X224285Y96750D03*
X258741Y193852D03*
X256823Y221979D03*
X246169Y246270D03*
X230774Y270268D03*
X241694Y274956D03*
X228635Y385956D03*
X232788Y385893D03*
X229764Y513034D03*
X234416Y512963D03*
X238924Y512390D03*
X243100Y516300D03*
X245963Y511890D03*
X250975Y511729D03*
X255500Y514000D03*
X264000Y513400D03*
X277300Y572500D03*
X259600Y568400D03*
X271949Y648699D03*
X272588Y681087D03*
X244248Y682153D03*
X255542Y665532D03*
X241904Y652321D03*
X289634Y659352D03*
X284520Y743307D03*
X282176Y713475D03*
X230823Y823850D03*
X253623Y867319D03*
X254262Y899707D03*
X225922Y900773D03*
X237216Y884152D03*
X223578Y870941D03*
X285585Y897363D03*
X283241Y867531D03*
X264212Y903112D03*
X299300Y41300D03*
X321300Y43200D03*
X351800Y42200D03*
X360500Y42600D03*
X330000Y42800D03*
X329900Y37100D03*
X321300D03*
X360500Y36700D03*
X291373Y47394D03*
X299300Y46400D03*
X351800Y36300D03*
X299600Y62100D03*
X351900Y62000D03*
X360200Y62300D03*
X329500Y62600D03*
X321300Y63100D03*
X325006Y15636D03*
X299500Y68200D03*
X352000Y68000D03*
X360200Y68200D03*
X329600D03*
X321400Y68500D03*
X344663Y108965D03*
X312275Y98098D03*
X354197Y158187D03*
X301140Y161383D03*
X352066Y262596D03*
X307320Y223390D03*
X301781Y258122D03*
X322022Y279856D03*
X320207Y428442D03*
X320166Y432442D03*
X309648Y582024D03*
X319679Y655730D03*
X320318Y688118D03*
X291978Y689184D03*
X303272Y672563D03*
X347378Y688332D03*
X358672Y671711D03*
X345034Y658500D03*
X302115Y693462D03*
X360803Y704312D03*
X333102Y737766D03*
X344396Y721145D03*
X330758Y707934D03*
X312221Y709853D03*
X312860Y742241D03*
X295814Y726686D03*
X319171Y767846D03*
X313959Y724732D03*
X354623Y896937D03*
X352279Y867105D03*
X313286Y863909D03*
X313925Y896297D03*
X296879Y880742D03*
X332436Y858576D03*
X337648Y901690D03*
X382100Y61900D03*
X401343Y58465D03*
X394098Y20059D03*
X362775D03*
X412506Y33484D03*
X382200Y68500D03*
X410025Y87658D03*
X390208Y180135D03*
X366982Y198886D03*
X407769Y204757D03*
X384668Y247681D03*
X376144Y279856D03*
X380956Y408290D03*
X376513Y408085D03*
X371865D03*
X380392Y416962D03*
X375949Y416757D03*
X371301D03*
X366653Y416484D03*
X367217Y407812D03*
X366719Y424200D03*
X371367Y424473D03*
X376015D03*
X380458Y424678D03*
X414894Y453432D03*
X419296Y449111D03*
X423572Y453454D03*
X419092Y457572D03*
X419225Y453324D03*
X410200Y474200D03*
X410179Y469769D03*
X375079Y654878D03*
X375718Y687266D03*
X430267Y679595D03*
X413860Y696428D03*
X400222Y683217D03*
X388817Y692040D03*
X420252Y725194D03*
X420891Y757582D03*
X392551Y758648D03*
X403845Y742027D03*
X390207Y728816D03*
X361442Y736700D03*
X430906Y711983D03*
X402566Y713049D03*
X395450Y767846D03*
X378868Y723311D03*
X421530Y814262D03*
X419186Y784430D03*
X429202Y894806D03*
X426858Y864974D03*
X382324Y863483D03*
X382963Y895871D03*
X365917Y880316D03*
X413927Y901690D03*
X397345Y857155D03*
X432682Y23909D03*
X472315Y23056D03*
X496393Y55871D03*
X457399Y46069D03*
X496109Y93412D03*
X457989Y78967D03*
X493200Y145500D03*
X451789Y154565D03*
X473097Y208901D03*
X453252Y250240D03*
X455846Y546626D03*
X465212Y726260D03*
X465851Y758648D03*
X437511Y759714D03*
X448805Y743093D03*
X435167Y729882D03*
X474587Y765253D03*
X445197Y719047D03*
X449231Y780808D03*
X449870Y813196D03*
X432824Y797641D03*
X476931Y795085D03*
X488225Y778464D03*
X499945Y828325D03*
X486307Y815114D03*
X456903Y861352D03*
X457542Y893740D03*
X440496Y878185D03*
X488651Y844946D03*
X499208Y899795D03*
X463674Y852891D03*
X557547Y24335D03*
X526213Y34431D03*
X555558Y100229D03*
X531425Y77545D03*
X545330Y147959D03*
X521476Y205704D03*
X509632Y174434D03*
X526688Y248818D03*
X566000Y536700D03*
X508224Y580873D03*
X549379Y653173D03*
X504632Y761631D03*
X505271Y794019D03*
X516352Y811492D03*
X562377Y833013D03*
X532332Y836635D03*
X516991Y843880D03*
X563016Y865401D03*
X534676Y866467D03*
X545970Y849846D03*
X545118Y880530D03*
X528711Y897363D03*
X515073Y884152D03*
X562590Y881808D03*
X510579Y854786D03*
X545757Y912918D03*
X517417Y913984D03*
X564934Y911640D03*
X573457Y59531D03*
X621826Y20111D03*
X591122Y33010D03*
X607704Y77545D03*
X586385Y204283D03*
X596334Y173012D03*
X602967Y248818D03*
X633923Y520400D03*
X587942Y582024D03*
X614582Y653599D03*
X604141Y675547D03*
X578784Y682152D03*
X582620Y653386D03*
X632693Y697281D03*
X607550Y703460D03*
X628006Y720720D03*
X592635Y878186D03*
X576228Y895019D03*
X640791Y876268D03*
X641430Y908656D03*
X613090Y909722D03*
X624384Y893101D03*
X610746Y879890D03*
X593274Y910574D03*
X660180Y56547D03*
X657451Y28746D03*
X703700Y30300D03*
X651658Y95968D03*
X692985Y75650D03*
X699619Y201914D03*
X652714Y200019D03*
X692512Y162589D03*
X661673Y260892D03*
X688248Y246923D03*
X712386Y297542D03*
X711500Y438300D03*
X694995Y453626D03*
X694923Y461253D03*
X694851Y469456D03*
X694907Y476993D03*
X668135Y523360D03*
X672161Y528021D03*
X676550Y523677D03*
X672342Y519560D03*
X672257Y523769D03*
X678293Y698772D03*
X675736Y657222D03*
X694061Y681726D03*
X654641Y691101D03*
X643987Y664041D03*
X697897Y662763D03*
X708231Y730948D03*
X681276Y722211D03*
X650805Y716671D03*
X698962Y707936D03*
X692356Y875629D03*
X692995Y908017D03*
X664655Y909083D03*
X675949Y892462D03*
X662311Y879251D03*
X754800Y56800D03*
Y36800D03*
Y16800D03*
X723466Y60810D03*
X721334Y17767D03*
X754800Y76800D03*
X754700Y117600D03*
Y97600D03*
X734333Y88085D03*
X754700Y197600D03*
Y177600D03*
Y157600D03*
Y137600D03*
Y257600D03*
Y237600D03*
Y217600D03*
Y277600D03*
X753800Y303200D03*
X767300Y340400D03*
X766900Y333754D03*
X735134Y289819D03*
X767000Y410900D03*
X766700Y403500D03*
X766900Y395400D03*
Y387800D03*
Y364600D03*
Y356300D03*
X767600Y348500D03*
X767400Y481600D03*
Y465900D03*
X767500Y450800D03*
X767300Y441747D03*
X766500Y435100D03*
X766800Y427000D03*
X767100Y418700D03*
Y544600D03*
X766800Y535700D03*
X767200Y524500D03*
X766900Y497700D03*
X767200Y489700D03*
X767100Y623900D03*
Y614800D03*
X766700Y606900D03*
X767700Y600200D03*
X766700Y592700D03*
X767000Y584300D03*
Y576100D03*
Y569500D03*
X726000Y650700D03*
X720000Y650800D03*
X733000Y650600D03*
X740000D03*
X766900Y639500D03*
Y631900D03*
X715795Y697494D03*
X750300Y663000D03*
X740513Y687906D03*
X745733Y713048D03*
X764200Y813000D03*
X745413Y854763D03*
X716221Y876694D03*
X729859Y889905D03*
X718565Y906526D03*
X746905Y905460D03*
X746266Y873072D03*
G54D18*
X22980Y59055D03*
X30854D03*
X22980Y106299D03*
Y98425D03*
Y90551D03*
Y82677D03*
Y74803D03*
Y66929D03*
X30854Y106299D03*
Y98425D03*
Y90551D03*
Y82677D03*
Y74803D03*
Y66929D03*
X41142Y135669D03*
Y155669D03*
Y145669D03*
X26181Y537559D03*
Y527559D03*
Y517559D03*
X41142Y655669D03*
Y645669D03*
Y635669D03*
Y763780D03*
Y753780D03*
Y773780D03*
G54D21*
X54724Y557087D03*
Y620079D03*
Y675197D03*
Y738189D03*
X144843Y798779D03*
Y874449D03*
G54D24*
X286982Y828335D03*
X276982D03*
X286982Y818335D03*
X276982D03*
X356982Y828335D03*
X346982D03*
X336982D03*
X326982D03*
X316982D03*
X306982D03*
X296982D03*
X356982Y818335D03*
X346982D03*
X336982D03*
X326982D03*
X316982D03*
X306982D03*
X296982D03*
X366982Y828335D03*
Y818335D03*
G54D20*
X53547Y322486D03*
Y302486D03*
X182681Y580832D03*
Y560832D03*
G54D23*
X144843Y812994D03*
Y860234D03*
G54D25*
X438300Y481200D03*
G54D11*
X-138100Y222300D03*
Y241300D03*
Y260300D03*
Y279300D03*
Y298300D03*
Y317300D03*
Y336300D03*
X-70100Y222300D03*
X-87100D03*
X-104100D03*
X-121100D03*
X-70100Y241300D03*
X-87100D03*
X-104100D03*
X-121100D03*
X-70100Y260300D03*
X-87100D03*
X-104100D03*
X-121100D03*
X-70100Y279300D03*
X-87100D03*
X-104100D03*
X-121100D03*
X-70100Y298300D03*
X-87100D03*
X-104100D03*
X-121100D03*
X-70100Y317300D03*
X-87100D03*
X-104100D03*
X-121100D03*
X-70100Y336300D03*
X-87100D03*
X-104100D03*
X-121100D03*
X-2100Y222300D03*
X-19100D03*
X-36100D03*
X-53100D03*
X-2100Y241300D03*
X-19100D03*
X-36100D03*
X-53100D03*
X-2100Y260300D03*
X-19100D03*
X-36300Y260000D03*
X-53100Y260300D03*
X-1900Y288300D03*
X-49400Y284500D03*
X-19600Y279500D03*
X-36100Y279300D03*
X-2100Y298300D03*
X-19100D03*
X-36100D03*
X-53100D03*
X-2100Y317300D03*
X-19100D03*
X-36100D03*
X-53100D03*
X-2100Y336300D03*
X-19100D03*
X-36100D03*
X-53100D03*
X-1600Y413600D03*
Y394600D03*
Y375600D03*
Y356600D03*
X-52600Y413600D03*
X-35600D03*
X-18600D03*
X-52600Y394600D03*
X-35600D03*
X-18600D03*
X-52600Y375600D03*
X-35600D03*
X-18600D03*
X-52600Y356600D03*
X-35600D03*
X-18600D03*
X-19400Y483400D03*
X-2400D03*
X-36400D03*
X-53400D03*
X-1500Y470300D03*
Y451300D03*
Y432300D03*
X-52500Y470300D03*
X-35500D03*
X-18500D03*
X-52500Y451300D03*
X-35500D03*
X-18500D03*
X-52500Y432300D03*
X-35500D03*
X-18500D03*
X-19400Y502400D03*
X-2400D03*
X-36400D03*
X-53400D03*
X63400Y89300D03*
X51900Y83600D03*
X69800Y176800D03*
X31500Y185700D03*
X60009Y255077D03*
X55624Y255132D03*
X59523Y271123D03*
X60102Y263180D03*
X55883Y263570D03*
X33400Y266400D03*
X59258Y246890D03*
X60069Y237965D03*
X64700Y215100D03*
X51600Y217000D03*
X42507Y296616D03*
X59316Y300366D03*
X59096Y289139D03*
X59523Y281330D03*
X52257Y276649D03*
X55420Y288656D03*
X17100Y311700D03*
X62439Y413744D03*
X66931Y398350D03*
X61776Y367194D03*
X74863Y390483D03*
X43345Y386857D03*
X43639Y374043D03*
X66963Y473083D03*
X51422Y473540D03*
X79081Y465348D03*
X70704Y429620D03*
X67015Y449433D03*
X74639Y441855D03*
X78754Y453353D03*
X78811Y426113D03*
X52151Y456887D03*
X66903Y457689D03*
X38800Y535700D03*
X38200Y528900D03*
X39600Y494800D03*
X38200Y490900D03*
X35100Y494400D03*
X59379Y644787D03*
X57500Y662600D03*
X60122Y747800D03*
X64000Y765600D03*
X106300Y105900D03*
X81150Y120850D03*
X89400Y120800D03*
X85250Y120850D03*
X117500Y106200D03*
X85000Y107800D03*
X111700Y106100D03*
X89000Y107700D03*
X125700Y225200D03*
X121000Y225300D03*
X109400Y225400D03*
X90813D03*
X79800Y225900D03*
X109534Y314564D03*
X145771Y414191D03*
X82555Y406288D03*
X95400Y383083D03*
X110472Y394496D03*
X145765Y406438D03*
X122053Y406224D03*
X114175Y410161D03*
X125990Y394413D03*
X141738D03*
X98427Y414098D03*
X125990D03*
X90553Y410161D03*
X102263Y414083D03*
X141887Y410202D03*
X102364Y406224D03*
X133864Y410161D03*
X94367Y394479D03*
X137801Y453472D03*
Y445598D03*
X133864Y437720D03*
Y445598D03*
X133953Y425813D03*
X133864Y433783D03*
X149612Y445598D03*
Y433783D03*
X137801Y477094D03*
X149612D03*
X114175D03*
X102364D03*
X98626Y477049D03*
X130081Y425912D03*
X121943Y425834D03*
X114091Y425962D03*
X122053Y421972D03*
Y418035D03*
X106301D03*
X114175D03*
X133863Y417883D03*
X110238Y453472D03*
X122053Y429846D03*
X114063Y429879D03*
X125897Y453240D03*
X118238Y453417D03*
X183120Y266103D03*
X183082Y271969D03*
X182853Y256107D03*
X183956Y261452D03*
X168010Y267909D03*
X219717Y211198D03*
X182177Y251208D03*
X154300Y227900D03*
X171200Y233000D03*
X185563Y245456D03*
X175064Y232857D03*
X185740Y240983D03*
X185502Y237383D03*
X183043Y276658D03*
X183707Y289861D03*
X183653Y283162D03*
X181576Y407810D03*
X175463Y413760D03*
X161499Y402554D03*
X169297Y402536D03*
X157502Y390427D03*
X173425Y390228D03*
X177588Y482616D03*
X161423Y469220D03*
X153583Y461058D03*
X169297Y477094D03*
Y465283D03*
X213400Y434601D03*
X157486Y437720D03*
Y429846D03*
X153416Y445539D03*
X169290Y417960D03*
X169297Y437720D03*
X169112Y453260D03*
X169166Y429679D03*
X181414Y490281D03*
X231350Y222067D03*
X257400Y403206D03*
X239600Y405600D03*
X237800Y411200D03*
X226576Y401835D03*
X246502Y472752D03*
X255622Y461532D03*
X263000Y438800D03*
X260600Y435900D03*
X258299Y432800D03*
X250400Y440000D03*
X249600Y428100D03*
X237700Y458000D03*
X271970Y798668D03*
X282413Y798410D03*
X228021Y787335D03*
X223596Y782163D03*
X295115Y476433D03*
Y473033D03*
X297715Y479588D03*
X306603Y459523D03*
X346510Y796385D03*
X350765D03*
X315696Y798445D03*
X294148Y798547D03*
X305437Y798205D03*
X361814Y796557D03*
X500295Y401715D03*
X501800Y387600D03*
X434515Y483333D03*
X434412Y479334D03*
X432014Y476132D03*
X483530Y541762D03*
X487073Y554094D03*
X482183Y535169D03*
X483008Y500529D03*
X469932Y518034D03*
X447307Y511890D03*
X447090Y497242D03*
X523200Y399400D03*
X506100Y380000D03*
X514073Y552477D03*
X629100Y536000D03*
X671915Y543133D03*
X694700Y547700D03*
X688800Y540450D03*
X702400Y554800D03*
X705927Y538650D03*
X663600Y535395D03*
X644600Y556700D03*
X652400Y545200D03*
X644900Y538300D03*
X674375Y509826D03*
X700512Y510204D03*
X669200Y559600D03*
X656817Y567131D03*
X689945Y758289D03*
X691075Y820814D03*
X729700Y551500D03*
X729600Y540400D03*
X724000Y532600D03*
X722682Y538700D03*
X716300Y517125D03*
X717879Y564572D03*
X729250Y850000D03*
G54D14*
X-33503Y269685D03*
G54D26*
X716535Y39370D03*
G54D19*
X29528Y19685D03*
X76772D03*
X108268Y905512D03*
X155512D03*
G54D22*
X109410Y796831D03*
Y876397D03*
X168465Y796831D03*
Y876397D03*
G54D10*
X-1011811Y-15748D03*
Y940945D03*
X775591Y-15748D03*
Y940944D03*
G54D12*
X-59094Y277559D03*
X-7913D03*
%LPC*%
G75*
G54D27*
G01X-771361Y-182763D02*
Y-262763D01*
G01Y-218263D02*
X373639D01*
G01X-771361Y-262763D02*
X373639D01*
G01X-775361Y-166763D02*
G02I-12000J0D01*
G01X-780511D02*
G02I-6850J0D01*
G01X-787361Y-182763D02*
Y-150763D01*
G01X-771361Y-166763D02*
X-803361D01*
G01X-771361Y-182763D02*
X373639D01*
G01X-413861D02*
Y-262763D01*
G01X-276361Y-182763D02*
Y-262763D01*
G01X-161361Y-182763D02*
Y-262763D01*
G01X6139Y-182763D02*
Y-262763D01*
G01X176139Y-182763D02*
Y-262763D01*
G01X373639Y-182763D02*
Y-262763D01*
G01X401639Y-166763D02*
G02I-12000J0D01*
G01X396489D02*
G02I-6850J0D01*
G01X389639Y-182763D02*
Y-150763D01*
G01X405639Y-166763D02*
X373639D01*
G54D28*
G01X-755164Y-252763D02*
Y-235263D01*
G01X-746868D02*
X-755164Y-246055D01*
G01X-745558Y-252763D02*
X-751453Y-241097D01*
G01X-737883Y-252763D02*
Y-235263D01*
X-727839Y-252763D01*
Y-235263D01*
G01X-715361Y-252763D02*
X-717108Y-252471D01*
X-718636Y-251305D01*
X-719946Y-249555D01*
X-720820Y-247513D01*
X-721256Y-245180D01*
Y-242846D01*
X-720820Y-240513D01*
X-719946Y-238471D01*
X-718636Y-236722D01*
X-717108Y-235555D01*
X-715361Y-235263D01*
X-713615Y-235555D01*
X-712086Y-236722D01*
X-710776Y-238471D01*
X-709902Y-240513D01*
X-709466Y-242846D01*
Y-245180D01*
X-709902Y-247513D01*
X-710776Y-249555D01*
X-712086Y-251305D01*
X-713615Y-252471D01*
X-715361Y-252763D01*
G01X-702446D02*
X-693276Y-235263D01*
G01X-702446D02*
X-693276Y-252763D01*
G01X-658494D02*
X-667228D01*
Y-235263D01*
X-658494D01*
G01X-661988Y-243721D02*
X-667228D01*
G01X-649946Y-252763D02*
X-640776Y-235263D01*
G01X-649946D02*
X-640776Y-252763D01*
G01X-632228D02*
Y-235263D01*
X-626988D01*
X-625241Y-236138D01*
X-623931Y-238180D01*
X-623494Y-240513D01*
X-623931Y-242846D01*
X-625023Y-244596D01*
X-626988Y-245472D01*
X-632228D01*
G01X-615820Y-252763D02*
X-610361Y-235263D01*
X-604902Y-252763D01*
G01X-606868Y-246638D02*
X-613855D01*
G01X-597883Y-252763D02*
Y-235263D01*
X-587839Y-252763D01*
Y-235263D01*
G01X-580164Y-252763D02*
Y-235263D01*
X-575798D01*
X-574051Y-236138D01*
X-572741Y-237305D01*
X-571649Y-239054D01*
X-570776Y-241097D01*
X-570558Y-244013D01*
X-570776Y-246930D01*
X-571649Y-248972D01*
X-572741Y-250722D01*
X-574051Y-251888D01*
X-575798Y-252763D01*
X-580164D01*
G01X-553494D02*
X-562228D01*
Y-235263D01*
X-553494D01*
G01X-556988Y-243721D02*
X-562228D01*
G01X-544728Y-252763D02*
Y-235263D01*
X-539269D01*
X-537523Y-236138D01*
X-536431Y-237305D01*
X-535994Y-239638D01*
X-536431Y-241972D01*
X-537741Y-243430D01*
X-539269Y-244305D01*
X-544728D01*
G01X-539269D02*
X-535994Y-252763D01*
G01X-503615Y-243430D02*
X-502741Y-242555D01*
X-502086Y-241097D01*
X-501649Y-239054D01*
X-502086Y-237305D01*
X-502959Y-236138D01*
X-504488Y-235263D01*
X-510383D01*
Y-252763D01*
X-503178D01*
X-501649Y-251597D01*
X-500776Y-249846D01*
X-500339Y-247805D01*
X-500776Y-245763D01*
X-502086Y-244013D01*
X-503615Y-243430D01*
X-510383D01*
G01X-487861Y-252763D02*
X-489608Y-252471D01*
X-491136Y-251305D01*
X-492446Y-249555D01*
X-493320Y-247513D01*
X-493756Y-245180D01*
Y-242846D01*
X-493320Y-240513D01*
X-492446Y-238471D01*
X-491136Y-236722D01*
X-489608Y-235555D01*
X-487861Y-235263D01*
X-486115Y-235555D01*
X-484586Y-236722D01*
X-483276Y-238471D01*
X-482402Y-240513D01*
X-481966Y-242846D01*
Y-245180D01*
X-482402Y-247513D01*
X-483276Y-249555D01*
X-484586Y-251305D01*
X-486115Y-252471D01*
X-487861Y-252763D01*
G01X-475820D02*
X-470361Y-235263D01*
X-464902Y-252763D01*
G01X-466868Y-246638D02*
X-473855D01*
G01X-457228Y-252763D02*
Y-235263D01*
X-451769D01*
X-450023Y-236138D01*
X-448931Y-237305D01*
X-448494Y-239638D01*
X-448931Y-241972D01*
X-450241Y-243430D01*
X-451769Y-244305D01*
X-457228D01*
G01X-451769D02*
X-448494Y-252763D01*
G01X-440164D02*
Y-235263D01*
X-435798D01*
X-434051Y-236138D01*
X-432741Y-237305D01*
X-431649Y-239054D01*
X-430776Y-241097D01*
X-430558Y-244013D01*
X-430776Y-246930D01*
X-431649Y-248972D01*
X-432741Y-250722D01*
X-434051Y-251888D01*
X-435798Y-252763D01*
X-440164D01*
G01X-633538Y-207763D02*
Y-190263D01*
X-627861Y-204846D01*
X-622184Y-190263D01*
Y-207763D01*
G01X-610361D02*
X-611671Y-207471D01*
X-612981Y-206305D01*
X-613855Y-204263D01*
X-614291Y-201930D01*
X-613855Y-199596D01*
X-612981Y-197555D01*
X-611671Y-196388D01*
X-610361Y-196097D01*
X-609051Y-196388D01*
X-607741Y-197555D01*
X-606868Y-199596D01*
X-606649Y-201930D01*
X-606868Y-204263D01*
X-607741Y-206305D01*
X-609051Y-207471D01*
X-610361Y-207763D01*
G01X-588931Y-190263D02*
Y-207763D01*
G01Y-205139D02*
X-589804Y-206597D01*
X-591115Y-207471D01*
X-592643Y-207763D01*
X-594389Y-207180D01*
X-595699Y-205722D01*
X-596573Y-203972D01*
X-596791Y-201930D01*
X-596573Y-199888D01*
X-595699Y-198138D01*
X-594389Y-196680D01*
X-592643Y-196097D01*
X-591115Y-196388D01*
X-590023Y-196972D01*
X-588931Y-198138D01*
G01X-578636Y-199888D02*
X-571649D01*
X-572304Y-197846D01*
X-573396Y-196680D01*
X-574924Y-196097D01*
X-576453Y-196388D01*
X-577763Y-197263D01*
X-578636Y-199305D01*
X-579073Y-201055D01*
Y-202805D01*
X-578636Y-204555D01*
X-577544Y-206305D01*
X-576234Y-207471D01*
X-574706Y-207763D01*
X-573178Y-207180D01*
X-571649Y-205430D01*
G01X-557861Y-207763D02*
Y-190263D01*
G01X-380161Y-252763D02*
Y-235263D01*
X-382781Y-238763D01*
G01Y-252763D02*
X-377541D01*
G01X-366809Y-238180D02*
X-365499Y-236430D01*
X-363971Y-235555D01*
X-362224Y-235263D01*
X-360041Y-235846D01*
X-358513Y-237305D01*
X-358076Y-239054D01*
X-358294Y-240805D01*
X-359168Y-242263D01*
X-363534Y-245180D01*
X-365499Y-247221D01*
X-366809Y-250139D01*
X-367246Y-252763D01*
X-358076D01*
G01X-345161Y-235263D02*
X-346908Y-235846D01*
X-348218Y-237305D01*
X-349091Y-239054D01*
X-349746Y-241388D01*
X-349964Y-244013D01*
X-349746Y-246638D01*
X-349091Y-248972D01*
X-348218Y-250722D01*
X-346908Y-252180D01*
X-345161Y-252763D01*
X-343415Y-252180D01*
X-342104Y-250722D01*
X-341231Y-248972D01*
X-340576Y-246638D01*
X-340358Y-244013D01*
X-340576Y-241388D01*
X-341231Y-239054D01*
X-342104Y-237305D01*
X-343415Y-235846D01*
X-345161Y-235263D01*
G01X-327661D02*
X-329408Y-235846D01*
X-330718Y-237305D01*
X-331591Y-239054D01*
X-332246Y-241388D01*
X-332464Y-244013D01*
X-332246Y-246638D01*
X-331591Y-248972D01*
X-330718Y-250722D01*
X-329408Y-252180D01*
X-327661Y-252763D01*
X-325915Y-252180D01*
X-324604Y-250722D01*
X-323731Y-248972D01*
X-323076Y-246638D01*
X-322858Y-244013D01*
X-323076Y-241388D01*
X-323731Y-239054D01*
X-324604Y-237305D01*
X-325915Y-235846D01*
X-327661Y-235263D01*
G01X-307541Y-252763D02*
Y-235263D01*
X-315620Y-247805D01*
X-304702D01*
G01X-393278Y-207763D02*
Y-190263D01*
X-388038D01*
X-386291Y-191138D01*
X-384981Y-193180D01*
X-384544Y-195513D01*
X-384981Y-197846D01*
X-386073Y-199596D01*
X-388038Y-200472D01*
X-393278D01*
G01X-366608Y-191722D02*
X-367918Y-190846D01*
X-369446Y-190263D01*
X-371193D01*
X-373158Y-191138D01*
X-374686Y-192596D01*
X-375778Y-194347D01*
X-376651Y-197263D01*
X-376870Y-199888D01*
X-376433Y-202513D01*
X-375778Y-204263D01*
X-374468Y-206013D01*
X-372939Y-207180D01*
X-371411Y-207763D01*
X-369883D01*
X-368354Y-207180D01*
X-367044Y-206305D01*
X-365952Y-205139D01*
G01X-352165Y-198430D02*
X-351291Y-197555D01*
X-350636Y-196097D01*
X-350199Y-194054D01*
X-350636Y-192305D01*
X-351509Y-191138D01*
X-353038Y-190263D01*
X-358933D01*
Y-207763D01*
X-351728D01*
X-350199Y-206597D01*
X-349326Y-204846D01*
X-348889Y-202805D01*
X-349326Y-200763D01*
X-350636Y-199013D01*
X-352165Y-198430D01*
X-358933D01*
G01X-342961Y-213596D02*
X-329861D01*
G01X-323933Y-207763D02*
Y-190263D01*
X-313889Y-207763D01*
Y-190263D01*
G01X-301411Y-207763D02*
X-303158Y-207471D01*
X-304686Y-206305D01*
X-305996Y-204555D01*
X-306870Y-202513D01*
X-307306Y-200180D01*
Y-197846D01*
X-306870Y-195513D01*
X-305996Y-193471D01*
X-304686Y-191722D01*
X-303158Y-190555D01*
X-301411Y-190263D01*
X-299665Y-190555D01*
X-298136Y-191722D01*
X-296826Y-193471D01*
X-295952Y-195513D01*
X-295516Y-197846D01*
Y-200180D01*
X-295952Y-202513D01*
X-296826Y-204555D01*
X-298136Y-206305D01*
X-299665Y-207471D01*
X-301411Y-207763D01*
G01X-218861Y-252763D02*
Y-235263D01*
X-221481Y-238763D01*
G01Y-252763D02*
X-216241D01*
G01X-250570Y-190263D02*
X-245111Y-207763D01*
X-239652Y-190263D01*
G01X-223244Y-207763D02*
X-231978D01*
Y-190263D01*
X-223244D01*
G01X-226738Y-198721D02*
X-231978D01*
G01X-214478Y-207763D02*
Y-190263D01*
X-209019D01*
X-207273Y-191138D01*
X-206181Y-192305D01*
X-205744Y-194638D01*
X-206181Y-196972D01*
X-207491Y-198430D01*
X-209019Y-199305D01*
X-214478D01*
G01X-209019D02*
X-205744Y-207763D01*
G01X-192611Y-208346D02*
X-193048Y-208055D01*
Y-207471D01*
X-192611Y-207180D01*
X-192174Y-207471D01*
Y-208055D01*
X-192611Y-208346D01*
G01X-117028Y-235263D02*
Y-252763D01*
X-108294D01*
G01X-92541D02*
Y-235263D01*
X-100620Y-247805D01*
X-89702D01*
G01X-83120Y-235263D02*
X-77661Y-252763D01*
X-72202Y-235263D01*
G01X-55358Y-236722D02*
X-56668Y-235846D01*
X-58196Y-235263D01*
X-59943D01*
X-61908Y-236138D01*
X-63436Y-237596D01*
X-64528Y-239347D01*
X-65401Y-242263D01*
X-65620Y-244888D01*
X-65183Y-247513D01*
X-64528Y-249263D01*
X-63218Y-251013D01*
X-61689Y-252180D01*
X-60161Y-252763D01*
X-58633D01*
X-57104Y-252180D01*
X-55794Y-251305D01*
X-54702Y-250139D01*
G01X-37858Y-236722D02*
X-39168Y-235846D01*
X-40696Y-235263D01*
X-42443D01*
X-44408Y-236138D01*
X-45936Y-237596D01*
X-47028Y-239347D01*
X-47901Y-242263D01*
X-48120Y-244888D01*
X-47683Y-247513D01*
X-47028Y-249263D01*
X-45718Y-251013D01*
X-44189Y-252180D01*
X-42661Y-252763D01*
X-41133D01*
X-39604Y-252180D01*
X-38294Y-251305D01*
X-37202Y-250139D01*
G01X-125778Y-190263D02*
Y-207763D01*
X-117044D01*
G01X-99981D02*
Y-196097D01*
G01Y-198138D02*
X-100854Y-196972D01*
X-102165Y-196388D01*
X-103693Y-196097D01*
X-105221Y-196680D01*
X-106531Y-197846D01*
X-107405Y-199596D01*
X-107841Y-201930D01*
X-107405Y-204263D01*
X-106531Y-206013D01*
X-105221Y-207180D01*
X-103693Y-207763D01*
X-102165Y-207471D01*
X-100854Y-206597D01*
X-99981Y-205430D01*
G01X-90996Y-213013D02*
X-89686Y-213596D01*
X-87939Y-213013D01*
X-86848Y-211847D01*
X-85974Y-210388D01*
X-84665Y-205722D01*
X-81826Y-196097D01*
G01X-88813D02*
X-84665Y-205722D01*
G01X-72186Y-199888D02*
X-65199D01*
X-65854Y-197846D01*
X-66946Y-196680D01*
X-68474Y-196097D01*
X-70003Y-196388D01*
X-71313Y-197263D01*
X-72186Y-199305D01*
X-72623Y-201055D01*
Y-202805D01*
X-72186Y-204555D01*
X-71094Y-206305D01*
X-69784Y-207471D01*
X-68256Y-207763D01*
X-66728Y-207180D01*
X-65199Y-205430D01*
G01X-54468Y-207763D02*
Y-196097D01*
G01Y-198430D02*
X-53376Y-197263D01*
X-52284Y-196388D01*
X-50756Y-196097D01*
X-49665Y-196388D01*
X-48354Y-197263D01*
G01X-37186Y-205722D02*
X-36094Y-206888D01*
X-34566Y-207763D01*
X-33256D01*
X-31946Y-207180D01*
X-31073Y-206305D01*
X-30636Y-205139D01*
X-30854Y-203388D01*
X-31728Y-202513D01*
X-35658Y-200763D01*
X-36531Y-198721D01*
X-36094Y-197263D01*
X-35221Y-196388D01*
X-33911Y-196097D01*
X-32601Y-196388D01*
X-31291Y-197263D01*
G01X51772Y-235263D02*
Y-252763D01*
X60506D01*
G01X68836Y-235263D02*
Y-247805D01*
X69709Y-250430D01*
X71456Y-252180D01*
X73639Y-252763D01*
X75822Y-252180D01*
X77569Y-250430D01*
X78442Y-247805D01*
Y-235263D01*
G01X95942Y-236722D02*
X94632Y-235846D01*
X93104Y-235263D01*
X91357D01*
X89392Y-236138D01*
X87864Y-237596D01*
X86772Y-239347D01*
X85899Y-242263D01*
X85680Y-244888D01*
X86117Y-247513D01*
X86772Y-249263D01*
X88082Y-251013D01*
X89611Y-252180D01*
X91139Y-252763D01*
X92667D01*
X94196Y-252180D01*
X95506Y-251305D01*
X96598Y-250139D01*
G01X103836Y-252763D02*
Y-235263D01*
G01X112132D02*
X103836Y-246055D01*
G01X113442Y-252763D02*
X107547Y-241097D01*
G01X126139Y-252763D02*
Y-244888D01*
X121772Y-235263D01*
G01X130506D02*
X126139Y-244888D01*
G01X25086Y-207763D02*
Y-190263D01*
X29452D01*
X31199Y-191138D01*
X32509Y-192305D01*
X33601Y-194054D01*
X34474Y-196097D01*
X34692Y-199013D01*
X34474Y-201930D01*
X33601Y-203972D01*
X32509Y-205722D01*
X31199Y-206888D01*
X29452Y-207763D01*
X25086D01*
G01X44114Y-199888D02*
X51101D01*
X50446Y-197846D01*
X49354Y-196680D01*
X47826Y-196097D01*
X46297Y-196388D01*
X44987Y-197263D01*
X44114Y-199305D01*
X43677Y-201055D01*
Y-202805D01*
X44114Y-204555D01*
X45206Y-206305D01*
X46516Y-207471D01*
X48044Y-207763D01*
X49572Y-207180D01*
X51101Y-205430D01*
G01X61614Y-205722D02*
X62706Y-206888D01*
X64234Y-207763D01*
X65544D01*
X66854Y-207180D01*
X67727Y-206305D01*
X68164Y-205139D01*
X67946Y-203388D01*
X67072Y-202513D01*
X63142Y-200763D01*
X62269Y-198721D01*
X62706Y-197263D01*
X63579Y-196388D01*
X64889Y-196097D01*
X66199Y-196388D01*
X67509Y-197263D01*
G01X82389Y-196097D02*
Y-207763D01*
G01Y-191430D02*
X81952Y-191138D01*
Y-190555D01*
X82389Y-190263D01*
X82826Y-190555D01*
Y-191138D01*
X82389Y-191430D01*
G01X96832Y-212138D02*
X98361Y-213305D01*
X100107Y-213596D01*
X101635Y-213305D01*
X102946Y-211847D01*
X103819Y-209805D01*
Y-196097D01*
G01Y-198430D02*
X102946Y-197263D01*
X101635Y-196388D01*
X100107Y-196097D01*
X98361Y-196680D01*
X97269Y-197846D01*
X96395Y-199888D01*
X95959Y-201930D01*
X96177Y-203680D01*
X97051Y-205722D01*
X98361Y-207180D01*
X100107Y-207763D01*
X101417Y-207471D01*
X102946Y-206305D01*
X103819Y-205139D01*
G01X113677Y-207763D02*
Y-196097D01*
G01Y-199013D02*
X114551Y-197555D01*
X115861Y-196388D01*
X117607Y-196097D01*
X119135Y-196388D01*
X120446Y-197555D01*
X121101Y-199596D01*
Y-207763D01*
G01X131614Y-199888D02*
X138601D01*
X137946Y-197846D01*
X136854Y-196680D01*
X135326Y-196097D01*
X133797Y-196388D01*
X132487Y-197263D01*
X131614Y-199305D01*
X131177Y-201055D01*
Y-202805D01*
X131614Y-204555D01*
X132706Y-206305D01*
X134016Y-207471D01*
X135544Y-207763D01*
X137072Y-207180D01*
X138601Y-205430D01*
G01X149332Y-207763D02*
Y-196097D01*
G01Y-198430D02*
X150424Y-197263D01*
X151516Y-196388D01*
X153044Y-196097D01*
X154135Y-196388D01*
X155446Y-197263D01*
G01X196089Y-252763D02*
Y-235263D01*
X193469Y-238763D01*
G01Y-252763D02*
X198709D01*
G01X213589Y-235263D02*
X211842Y-235846D01*
X210532Y-237305D01*
X209659Y-239054D01*
X209004Y-241388D01*
X208786Y-244013D01*
X209004Y-246638D01*
X209659Y-248972D01*
X210532Y-250722D01*
X211842Y-252180D01*
X213589Y-252763D01*
X215335Y-252180D01*
X216646Y-250722D01*
X217519Y-248972D01*
X218174Y-246638D01*
X218392Y-244013D01*
X218174Y-241388D01*
X217519Y-239054D01*
X216646Y-237305D01*
X215335Y-235846D01*
X213589Y-235263D01*
G01X227159Y-253346D02*
X235019Y-235263D01*
G01X248589Y-252763D02*
Y-235263D01*
X245969Y-238763D01*
G01Y-252763D02*
X251209D01*
G01X261941Y-245472D02*
X263469Y-243430D01*
X264779Y-242263D01*
X266526Y-241680D01*
X268054Y-242263D01*
X269146Y-243430D01*
X270019Y-245180D01*
X270237Y-247221D01*
X270019Y-248972D01*
X269146Y-250722D01*
X267835Y-252180D01*
X266307Y-252763D01*
X264561Y-252180D01*
X263032Y-250430D01*
X262159Y-247805D01*
X261941Y-244888D01*
X262377Y-241097D01*
X263032Y-239054D01*
X264124Y-237013D01*
X265652Y-235555D01*
X267181Y-235263D01*
X268709Y-235846D01*
X269801Y-237305D01*
G01X279659Y-253346D02*
X287519Y-235263D01*
G01X296941Y-238180D02*
X298251Y-236430D01*
X299779Y-235555D01*
X301526Y-235263D01*
X303709Y-235846D01*
X305237Y-237305D01*
X305674Y-239054D01*
X305456Y-240805D01*
X304582Y-242263D01*
X300216Y-245180D01*
X298251Y-247221D01*
X296941Y-250139D01*
X296504Y-252763D01*
X305674D01*
G01X318589Y-235263D02*
X316842Y-235846D01*
X315532Y-237305D01*
X314659Y-239054D01*
X314004Y-241388D01*
X313786Y-244013D01*
X314004Y-246638D01*
X314659Y-248972D01*
X315532Y-250722D01*
X316842Y-252180D01*
X318589Y-252763D01*
X320335Y-252180D01*
X321646Y-250722D01*
X322519Y-248972D01*
X323174Y-246638D01*
X323392Y-244013D01*
X323174Y-241388D01*
X322519Y-239054D01*
X321646Y-237305D01*
X320335Y-235846D01*
X318589Y-235263D01*
G01X336089Y-252763D02*
Y-235263D01*
X333469Y-238763D01*
G01Y-252763D02*
X338709D01*
G01X349441Y-238180D02*
X350751Y-236430D01*
X352279Y-235555D01*
X354026Y-235263D01*
X356209Y-235846D01*
X357737Y-237305D01*
X358174Y-239054D01*
X357956Y-240805D01*
X357082Y-242263D01*
X352716Y-245180D01*
X350751Y-247221D01*
X349441Y-250139D01*
X349004Y-252763D01*
X358174D01*
G01X243786Y-207763D02*
Y-190263D01*
X248152D01*
X249899Y-191138D01*
X251209Y-192305D01*
X252301Y-194054D01*
X253174Y-196097D01*
X253392Y-199013D01*
X253174Y-201930D01*
X252301Y-203972D01*
X251209Y-205722D01*
X249899Y-206888D01*
X248152Y-207763D01*
X243786D01*
G01X270019D02*
Y-196097D01*
G01Y-198138D02*
X269146Y-196972D01*
X267835Y-196388D01*
X266307Y-196097D01*
X264779Y-196680D01*
X263469Y-197846D01*
X262595Y-199596D01*
X262159Y-201930D01*
X262595Y-204263D01*
X263469Y-206013D01*
X264779Y-207180D01*
X266307Y-207763D01*
X267835Y-207471D01*
X269146Y-206597D01*
X270019Y-205430D01*
G01X283589Y-190263D02*
Y-207763D01*
G01X280532Y-196097D02*
X286646D01*
G01X297814Y-199888D02*
X304801D01*
X304146Y-197846D01*
X303054Y-196680D01*
X301526Y-196097D01*
X299997Y-196388D01*
X298687Y-197263D01*
X297814Y-199305D01*
X297377Y-201055D01*
Y-202805D01*
X297814Y-204555D01*
X298906Y-206305D01*
X300216Y-207471D01*
X301744Y-207763D01*
X303272Y-207180D01*
X304801Y-205430D01*
M02*
